FILE_TYPE = MACRO_DRAWING;
SET COLOR_WIRE YELLOW;
SET COLOR_PROP ORANGE;
SET COLOR_DOT WHITE;
SET COLOR_ARC YELLOW;
SET COLOR_BODY GREEN;
SET COLOR_NOTE PURPLE;
SET PROP_DISPLAY VALUE;
SET PAGE_NUMBER P106;
FORCEADD OFFPAGE..6
(-8150 3525);
FORCEPROP 2 LAST $XR0 46 
J 0
(-8429 3525);
DISPLAY 0.638298 (-8429 3525);
PAINT MONO (-8429 3525);
FORCEPROP 2 LAST CDS_LIB mstr_standard
J 0
(-8150 3525);
DISPLAY 0.723404 (-8150 3525);
PAINT MONO (-8150 3525);
DISPLAY INVISIBLE (-8150 3525);
FORCEPROP 1 LAST OFFPAGE TRUE
J 0
(-7825 3400);
DISPLAY 0.872340 (-7825 3400);
PAINT GREEN (-7825 3400);
DISPLAY INVISIBLE (-7825 3400);
FORCEPROP 1 LAST COMMENT_BODY TRUE
J 0
(-8050 3450);
DISPLAY 0.872340 (-8050 3450);
PAINT GREEN (-8050 3450);
DISPLAY INVISIBLE (-8050 3450);
FORCEPROP 2 LAST PATH I10
J 0
(-8375 3575);
DISPLAY 1.021277 (-8375 3575);
DISPLAY INVISIBLE (-8375 3575);
FORCEADD TAP..1
(-5850 4125);
FORCEPROP 3 LASTPIN (-5900 4125) SIG_NAME M_J_CPU1_SA_DQ<7>
J 0
(-5890 4135);
DISPLAY 0.659574 (-5890 4135);
PAINT MONO (-5890 4135);
DISPLAY INVISIBLE (-5890 4135);
FORCEPROP 1 LASTPIN (-5900 4125) BN 7
J 0
(-5912 4133);
DISPLAY 0.489362 (-5912 4133);
PAINT GREEN (-5912 4133);
FORCEPROP 2 LAST CDS_LIB mstr_standard
J 0
(-5850 4125);
DISPLAY 0.723404 (-5850 4125);
PAINT MONO (-5850 4125);
DISPLAY INVISIBLE (-5850 4125);
FORCEPROP 1 LAST BODY_TYPE PLUMBING
J 0
(-5850 4175);
DISPLAY 0.872340 (-5850 4175);
PAINT GREEN (-5850 4175);
DISPLAY INVISIBLE (-5850 4175);
FORCEPROP 1 LAST HDL_TAP TRUE
J 0
(-5525 4000);
DISPLAY 0.872340 (-5525 4000);
DISPLAY INVISIBLE (-5525 4000);
FORCEPROP 1 LAST PATH I100
J 0
(-5852 4125);
DISPLAY 0.872340 (-5852 4125);
PAINT GREEN (-5852 4125);
DISPLAY INVISIBLE (-5852 4125);
FORCEADD TAP..1
(-5850 4175);
FORCEPROP 3 LASTPIN (-5900 4175) SIG_NAME M_J_CPU1_SA_DQ<8>
J 0
(-5890 4185);
DISPLAY 0.659574 (-5890 4185);
PAINT MONO (-5890 4185);
DISPLAY INVISIBLE (-5890 4185);
FORCEPROP 1 LASTPIN (-5900 4175) BN 8
J 0
(-5912 4183);
DISPLAY 0.489362 (-5912 4183);
PAINT GREEN (-5912 4183);
FORCEPROP 2 LAST CDS_LIB mstr_standard
J 0
(-5850 4175);
DISPLAY 0.723404 (-5850 4175);
PAINT MONO (-5850 4175);
DISPLAY INVISIBLE (-5850 4175);
FORCEPROP 1 LAST BODY_TYPE PLUMBING
J 0
(-5850 4225);
DISPLAY 0.872340 (-5850 4225);
PAINT GREEN (-5850 4225);
DISPLAY INVISIBLE (-5850 4225);
FORCEPROP 1 LAST HDL_TAP TRUE
J 0
(-5525 4050);
DISPLAY 0.872340 (-5525 4050);
DISPLAY INVISIBLE (-5525 4050);
FORCEPROP 1 LAST PATH I101
J 0
(-5852 4175);
DISPLAY 0.872340 (-5852 4175);
PAINT GREEN (-5852 4175);
DISPLAY INVISIBLE (-5852 4175);
FORCEADD TAP..1
(-5850 4225);
FORCEPROP 3 LASTPIN (-5900 4225) SIG_NAME M_J_CPU1_SA_DQ<9>
J 0
(-5890 4235);
DISPLAY 0.659574 (-5890 4235);
PAINT MONO (-5890 4235);
DISPLAY INVISIBLE (-5890 4235);
FORCEPROP 1 LASTPIN (-5900 4225) BN 9
J 0
(-5912 4233);
DISPLAY 0.489362 (-5912 4233);
PAINT GREEN (-5912 4233);
FORCEPROP 2 LAST CDS_LIB mstr_standard
J 0
(-5850 4225);
DISPLAY 0.723404 (-5850 4225);
PAINT MONO (-5850 4225);
DISPLAY INVISIBLE (-5850 4225);
FORCEPROP 1 LAST BODY_TYPE PLUMBING
J 0
(-5850 4275);
DISPLAY 0.872340 (-5850 4275);
PAINT GREEN (-5850 4275);
DISPLAY INVISIBLE (-5850 4275);
FORCEPROP 1 LAST HDL_TAP TRUE
J 0
(-5525 4100);
DISPLAY 0.872340 (-5525 4100);
DISPLAY INVISIBLE (-5525 4100);
FORCEPROP 1 LAST PATH I102
J 0
(-5852 4225);
DISPLAY 0.872340 (-5852 4225);
PAINT GREEN (-5852 4225);
DISPLAY INVISIBLE (-5852 4225);
FORCEADD TAP..1
(-5850 4275);
FORCEPROP 3 LASTPIN (-5900 4275) SIG_NAME M_J_CPU1_SA_DQ<10>
J 0
(-5890 4285);
DISPLAY 0.659574 (-5890 4285);
PAINT MONO (-5890 4285);
DISPLAY INVISIBLE (-5890 4285);
FORCEPROP 1 LASTPIN (-5900 4275) BN 10
J 0
(-5912 4283);
DISPLAY 0.489362 (-5912 4283);
PAINT GREEN (-5912 4283);
FORCEPROP 2 LAST CDS_LIB mstr_standard
J 0
(-5850 4275);
DISPLAY 0.723404 (-5850 4275);
PAINT MONO (-5850 4275);
DISPLAY INVISIBLE (-5850 4275);
FORCEPROP 1 LAST BODY_TYPE PLUMBING
J 0
(-5850 4325);
DISPLAY 0.872340 (-5850 4325);
PAINT GREEN (-5850 4325);
DISPLAY INVISIBLE (-5850 4325);
FORCEPROP 1 LAST HDL_TAP TRUE
J 0
(-5525 4150);
DISPLAY 0.872340 (-5525 4150);
DISPLAY INVISIBLE (-5525 4150);
FORCEPROP 1 LAST PATH I103
J 0
(-5852 4275);
DISPLAY 0.872340 (-5852 4275);
PAINT GREEN (-5852 4275);
DISPLAY INVISIBLE (-5852 4275);
FORCEADD TAP..1
(-5850 4375);
FORCEPROP 3 LASTPIN (-5900 4375) SIG_NAME M_J_CPU1_SA_DQ<12>
J 0
(-5890 4385);
DISPLAY 0.659574 (-5890 4385);
PAINT MONO (-5890 4385);
DISPLAY INVISIBLE (-5890 4385);
FORCEPROP 1 LASTPIN (-5900 4375) BN 12
J 0
(-5912 4383);
DISPLAY 0.489362 (-5912 4383);
PAINT GREEN (-5912 4383);
FORCEPROP 2 LAST CDS_LIB mstr_standard
J 0
(-5850 4375);
DISPLAY 0.723404 (-5850 4375);
PAINT MONO (-5850 4375);
DISPLAY INVISIBLE (-5850 4375);
FORCEPROP 1 LAST BODY_TYPE PLUMBING
J 0
(-5850 4425);
DISPLAY 0.872340 (-5850 4425);
PAINT GREEN (-5850 4425);
DISPLAY INVISIBLE (-5850 4425);
FORCEPROP 1 LAST HDL_TAP TRUE
J 0
(-5525 4250);
DISPLAY 0.872340 (-5525 4250);
DISPLAY INVISIBLE (-5525 4250);
FORCEPROP 1 LAST PATH I104
J 0
(-5852 4375);
DISPLAY 0.872340 (-5852 4375);
PAINT GREEN (-5852 4375);
DISPLAY INVISIBLE (-5852 4375);
FORCEADD TAP..1
(-5850 4325);
FORCEPROP 3 LASTPIN (-5900 4325) SIG_NAME M_J_CPU1_SA_DQ<11>
J 0
(-5890 4335);
DISPLAY 0.659574 (-5890 4335);
PAINT MONO (-5890 4335);
DISPLAY INVISIBLE (-5890 4335);
FORCEPROP 1 LASTPIN (-5900 4325) BN 11
J 0
(-5912 4333);
DISPLAY 0.489362 (-5912 4333);
PAINT GREEN (-5912 4333);
FORCEPROP 2 LAST CDS_LIB mstr_standard
J 0
(-5850 4325);
DISPLAY 0.723404 (-5850 4325);
PAINT MONO (-5850 4325);
DISPLAY INVISIBLE (-5850 4325);
FORCEPROP 1 LAST BODY_TYPE PLUMBING
J 0
(-5850 4375);
DISPLAY 0.872340 (-5850 4375);
PAINT GREEN (-5850 4375);
DISPLAY INVISIBLE (-5850 4375);
FORCEPROP 1 LAST HDL_TAP TRUE
J 0
(-5525 4200);
DISPLAY 0.872340 (-5525 4200);
DISPLAY INVISIBLE (-5525 4200);
FORCEPROP 1 LAST PATH I105
J 0
(-5852 4325);
DISPLAY 0.872340 (-5852 4325);
PAINT GREEN (-5852 4325);
DISPLAY INVISIBLE (-5852 4325);
FORCEADD TAP..1
(-5850 4425);
FORCEPROP 3 LASTPIN (-5900 4425) SIG_NAME M_J_CPU1_SA_DQ<13>
J 0
(-5890 4435);
DISPLAY 0.659574 (-5890 4435);
PAINT MONO (-5890 4435);
DISPLAY INVISIBLE (-5890 4435);
FORCEPROP 1 LASTPIN (-5900 4425) BN 13
J 0
(-5912 4433);
DISPLAY 0.489362 (-5912 4433);
PAINT GREEN (-5912 4433);
FORCEPROP 2 LAST CDS_LIB mstr_standard
J 0
(-5850 4425);
DISPLAY 0.723404 (-5850 4425);
PAINT MONO (-5850 4425);
DISPLAY INVISIBLE (-5850 4425);
FORCEPROP 1 LAST BODY_TYPE PLUMBING
J 0
(-5850 4475);
DISPLAY 0.872340 (-5850 4475);
PAINT GREEN (-5850 4475);
DISPLAY INVISIBLE (-5850 4475);
FORCEPROP 1 LAST HDL_TAP TRUE
J 0
(-5525 4300);
DISPLAY 0.872340 (-5525 4300);
DISPLAY INVISIBLE (-5525 4300);
FORCEPROP 1 LAST PATH I106
J 0
(-5852 4425);
DISPLAY 0.872340 (-5852 4425);
PAINT GREEN (-5852 4425);
DISPLAY INVISIBLE (-5852 4425);
FORCEADD TAP..1
(-5850 4475);
FORCEPROP 3 LASTPIN (-5900 4475) SIG_NAME M_J_CPU1_SA_DQ<14>
J 0
(-5890 4485);
DISPLAY 0.659574 (-5890 4485);
PAINT MONO (-5890 4485);
DISPLAY INVISIBLE (-5890 4485);
FORCEPROP 1 LASTPIN (-5900 4475) BN 14
J 0
(-5912 4483);
DISPLAY 0.489362 (-5912 4483);
PAINT GREEN (-5912 4483);
FORCEPROP 2 LAST CDS_LIB mstr_standard
J 0
(-5850 4475);
DISPLAY 0.723404 (-5850 4475);
PAINT MONO (-5850 4475);
DISPLAY INVISIBLE (-5850 4475);
FORCEPROP 1 LAST BODY_TYPE PLUMBING
J 0
(-5850 4525);
DISPLAY 0.872340 (-5850 4525);
PAINT GREEN (-5850 4525);
DISPLAY INVISIBLE (-5850 4525);
FORCEPROP 1 LAST HDL_TAP TRUE
J 0
(-5525 4350);
DISPLAY 0.872340 (-5525 4350);
DISPLAY INVISIBLE (-5525 4350);
FORCEPROP 1 LAST PATH I107
J 0
(-5852 4475);
DISPLAY 0.872340 (-5852 4475);
PAINT GREEN (-5852 4475);
DISPLAY INVISIBLE (-5852 4475);
FORCEADD TAP..1
(-5850 4525);
FORCEPROP 3 LASTPIN (-5900 4525) SIG_NAME M_J_CPU1_SA_DQ<15>
J 0
(-5890 4535);
DISPLAY 0.659574 (-5890 4535);
PAINT MONO (-5890 4535);
DISPLAY INVISIBLE (-5890 4535);
FORCEPROP 1 LASTPIN (-5900 4525) BN 15
J 0
(-5912 4533);
DISPLAY 0.489362 (-5912 4533);
PAINT GREEN (-5912 4533);
FORCEPROP 2 LAST CDS_LIB mstr_standard
J 0
(-5850 4525);
DISPLAY 0.723404 (-5850 4525);
PAINT MONO (-5850 4525);
DISPLAY INVISIBLE (-5850 4525);
FORCEPROP 1 LAST BODY_TYPE PLUMBING
J 0
(-5850 4575);
DISPLAY 0.872340 (-5850 4575);
PAINT GREEN (-5850 4575);
DISPLAY INVISIBLE (-5850 4575);
FORCEPROP 1 LAST HDL_TAP TRUE
J 0
(-5525 4400);
DISPLAY 0.872340 (-5525 4400);
DISPLAY INVISIBLE (-5525 4400);
FORCEPROP 1 LAST PATH I108
J 0
(-5852 4525);
DISPLAY 0.872340 (-5852 4525);
PAINT GREEN (-5852 4525);
DISPLAY INVISIBLE (-5852 4525);
FORCEADD TAP..1
(-5850 4575);
FORCEPROP 3 LASTPIN (-5900 4575) SIG_NAME M_J_CPU1_SA_DQ<16>
J 0
(-5890 4585);
DISPLAY 0.659574 (-5890 4585);
PAINT MONO (-5890 4585);
DISPLAY INVISIBLE (-5890 4585);
FORCEPROP 1 LASTPIN (-5900 4575) BN 16
J 0
(-5912 4583);
DISPLAY 0.489362 (-5912 4583);
PAINT GREEN (-5912 4583);
FORCEPROP 2 LAST CDS_LIB mstr_standard
J 0
(-5850 4575);
DISPLAY 0.723404 (-5850 4575);
PAINT MONO (-5850 4575);
DISPLAY INVISIBLE (-5850 4575);
FORCEPROP 1 LAST BODY_TYPE PLUMBING
J 0
(-5850 4625);
DISPLAY 0.872340 (-5850 4625);
PAINT GREEN (-5850 4625);
DISPLAY INVISIBLE (-5850 4625);
FORCEPROP 1 LAST HDL_TAP TRUE
J 0
(-5525 4450);
DISPLAY 0.872340 (-5525 4450);
DISPLAY INVISIBLE (-5525 4450);
FORCEPROP 1 LAST PATH I109
J 0
(-5852 4575);
DISPLAY 0.872340 (-5852 4575);
PAINT GREEN (-5852 4575);
DISPLAY INVISIBLE (-5852 4575);
FORCEADD OFFPAGE..6
(-8150 3975);
FORCEPROP 2 LAST $XR0 46 
J 0
(-8429 3975);
DISPLAY 0.638298 (-8429 3975);
PAINT MONO (-8429 3975);
FORCEPROP 2 LAST CDS_LIB mstr_standard
J 0
(-8150 3975);
DISPLAY 0.723404 (-8150 3975);
PAINT MONO (-8150 3975);
DISPLAY INVISIBLE (-8150 3975);
FORCEPROP 1 LAST OFFPAGE TRUE
J 0
(-7825 3850);
DISPLAY 0.872340 (-7825 3850);
PAINT GREEN (-7825 3850);
DISPLAY INVISIBLE (-7825 3850);
FORCEPROP 1 LAST COMMENT_BODY TRUE
J 0
(-8050 3900);
DISPLAY 0.872340 (-8050 3900);
PAINT GREEN (-8050 3900);
DISPLAY INVISIBLE (-8050 3900);
FORCEPROP 2 LAST PATH I11
J 0
(-8375 4025);
DISPLAY 1.021277 (-8375 4025);
DISPLAY INVISIBLE (-8375 4025);
FORCEADD TAP..1
(-5850 4625);
FORCEPROP 3 LASTPIN (-5900 4625) SIG_NAME M_J_CPU1_SA_DQ<17>
J 0
(-5890 4635);
DISPLAY 0.659574 (-5890 4635);
PAINT MONO (-5890 4635);
DISPLAY INVISIBLE (-5890 4635);
FORCEPROP 1 LASTPIN (-5900 4625) BN 17
J 0
(-5912 4633);
DISPLAY 0.489362 (-5912 4633);
PAINT GREEN (-5912 4633);
FORCEPROP 2 LAST CDS_LIB mstr_standard
J 0
(-5850 4625);
DISPLAY 0.723404 (-5850 4625);
PAINT MONO (-5850 4625);
DISPLAY INVISIBLE (-5850 4625);
FORCEPROP 1 LAST BODY_TYPE PLUMBING
J 0
(-5850 4675);
DISPLAY 0.872340 (-5850 4675);
PAINT GREEN (-5850 4675);
DISPLAY INVISIBLE (-5850 4675);
FORCEPROP 1 LAST HDL_TAP TRUE
J 0
(-5525 4500);
DISPLAY 0.872340 (-5525 4500);
DISPLAY INVISIBLE (-5525 4500);
FORCEPROP 1 LAST PATH I110
J 0
(-5852 4625);
DISPLAY 0.872340 (-5852 4625);
PAINT GREEN (-5852 4625);
DISPLAY INVISIBLE (-5852 4625);
FORCEADD TAP..1
(-5850 4675);
FORCEPROP 3 LASTPIN (-5900 4675) SIG_NAME M_J_CPU1_SA_DQ<18>
J 0
(-5890 4685);
DISPLAY 0.659574 (-5890 4685);
PAINT MONO (-5890 4685);
DISPLAY INVISIBLE (-5890 4685);
FORCEPROP 1 LASTPIN (-5900 4675) BN 18
J 0
(-5912 4683);
DISPLAY 0.489362 (-5912 4683);
PAINT GREEN (-5912 4683);
FORCEPROP 2 LAST CDS_LIB mstr_standard
J 0
(-5850 4675);
DISPLAY 0.723404 (-5850 4675);
PAINT MONO (-5850 4675);
DISPLAY INVISIBLE (-5850 4675);
FORCEPROP 1 LAST BODY_TYPE PLUMBING
J 0
(-5850 4725);
DISPLAY 0.872340 (-5850 4725);
PAINT GREEN (-5850 4725);
DISPLAY INVISIBLE (-5850 4725);
FORCEPROP 1 LAST HDL_TAP TRUE
J 0
(-5525 4550);
DISPLAY 0.872340 (-5525 4550);
DISPLAY INVISIBLE (-5525 4550);
FORCEPROP 1 LAST PATH I111
J 0
(-5852 4675);
DISPLAY 0.872340 (-5852 4675);
PAINT GREEN (-5852 4675);
DISPLAY INVISIBLE (-5852 4675);
FORCEADD TAP..1
(-5850 4725);
FORCEPROP 3 LASTPIN (-5900 4725) SIG_NAME M_J_CPU1_SA_DQ<19>
J 0
(-5890 4735);
DISPLAY 0.659574 (-5890 4735);
PAINT MONO (-5890 4735);
DISPLAY INVISIBLE (-5890 4735);
FORCEPROP 1 LASTPIN (-5900 4725) BN 19
J 0
(-5912 4733);
DISPLAY 0.489362 (-5912 4733);
PAINT GREEN (-5912 4733);
FORCEPROP 2 LAST CDS_LIB mstr_standard
J 0
(-5850 4725);
DISPLAY 0.723404 (-5850 4725);
PAINT MONO (-5850 4725);
DISPLAY INVISIBLE (-5850 4725);
FORCEPROP 1 LAST BODY_TYPE PLUMBING
J 0
(-5850 4775);
DISPLAY 0.872340 (-5850 4775);
PAINT GREEN (-5850 4775);
DISPLAY INVISIBLE (-5850 4775);
FORCEPROP 1 LAST HDL_TAP TRUE
J 0
(-5525 4600);
DISPLAY 0.872340 (-5525 4600);
DISPLAY INVISIBLE (-5525 4600);
FORCEPROP 1 LAST PATH I112
J 0
(-5852 4725);
DISPLAY 0.872340 (-5852 4725);
PAINT GREEN (-5852 4725);
DISPLAY INVISIBLE (-5852 4725);
FORCEADD TAP..1
(-5850 4775);
FORCEPROP 3 LASTPIN (-5900 4775) SIG_NAME M_J_CPU1_SA_DQ<20>
J 0
(-5890 4785);
DISPLAY 0.659574 (-5890 4785);
PAINT MONO (-5890 4785);
DISPLAY INVISIBLE (-5890 4785);
FORCEPROP 1 LASTPIN (-5900 4775) BN 20
J 0
(-5912 4783);
DISPLAY 0.489362 (-5912 4783);
PAINT GREEN (-5912 4783);
FORCEPROP 2 LAST CDS_LIB mstr_standard
J 0
(-5850 4775);
DISPLAY 0.723404 (-5850 4775);
PAINT MONO (-5850 4775);
DISPLAY INVISIBLE (-5850 4775);
FORCEPROP 1 LAST BODY_TYPE PLUMBING
J 0
(-5850 4825);
DISPLAY 0.872340 (-5850 4825);
PAINT GREEN (-5850 4825);
DISPLAY INVISIBLE (-5850 4825);
FORCEPROP 1 LAST HDL_TAP TRUE
J 0
(-5525 4650);
DISPLAY 0.872340 (-5525 4650);
DISPLAY INVISIBLE (-5525 4650);
FORCEPROP 1 LAST PATH I113
J 0
(-5852 4775);
DISPLAY 0.872340 (-5852 4775);
PAINT GREEN (-5852 4775);
DISPLAY INVISIBLE (-5852 4775);
FORCEADD TAP..1
(-5850 4825);
FORCEPROP 3 LASTPIN (-5900 4825) SIG_NAME M_J_CPU1_SA_DQ<21>
J 0
(-5890 4835);
DISPLAY 0.659574 (-5890 4835);
PAINT MONO (-5890 4835);
DISPLAY INVISIBLE (-5890 4835);
FORCEPROP 1 LASTPIN (-5900 4825) BN 21
J 0
(-5912 4833);
DISPLAY 0.489362 (-5912 4833);
PAINT GREEN (-5912 4833);
FORCEPROP 2 LAST CDS_LIB mstr_standard
J 0
(-5850 4825);
DISPLAY 0.723404 (-5850 4825);
PAINT MONO (-5850 4825);
DISPLAY INVISIBLE (-5850 4825);
FORCEPROP 1 LAST BODY_TYPE PLUMBING
J 0
(-5850 4875);
DISPLAY 0.872340 (-5850 4875);
PAINT GREEN (-5850 4875);
DISPLAY INVISIBLE (-5850 4875);
FORCEPROP 1 LAST HDL_TAP TRUE
J 0
(-5525 4700);
DISPLAY 0.872340 (-5525 4700);
DISPLAY INVISIBLE (-5525 4700);
FORCEPROP 1 LAST PATH I114
J 0
(-5852 4825);
DISPLAY 0.872340 (-5852 4825);
PAINT GREEN (-5852 4825);
DISPLAY INVISIBLE (-5852 4825);
FORCEADD TAP..1
(-5850 4875);
FORCEPROP 3 LASTPIN (-5900 4875) SIG_NAME M_J_CPU1_SA_DQ<22>
J 0
(-5890 4885);
DISPLAY 0.659574 (-5890 4885);
PAINT MONO (-5890 4885);
DISPLAY INVISIBLE (-5890 4885);
FORCEPROP 1 LASTPIN (-5900 4875) BN 22
J 0
(-5912 4883);
DISPLAY 0.489362 (-5912 4883);
PAINT GREEN (-5912 4883);
FORCEPROP 2 LAST CDS_LIB mstr_standard
J 0
(-5850 4875);
DISPLAY 0.723404 (-5850 4875);
PAINT MONO (-5850 4875);
DISPLAY INVISIBLE (-5850 4875);
FORCEPROP 1 LAST BODY_TYPE PLUMBING
J 0
(-5850 4925);
DISPLAY 0.872340 (-5850 4925);
PAINT GREEN (-5850 4925);
DISPLAY INVISIBLE (-5850 4925);
FORCEPROP 1 LAST HDL_TAP TRUE
J 0
(-5525 4750);
DISPLAY 0.872340 (-5525 4750);
DISPLAY INVISIBLE (-5525 4750);
FORCEPROP 1 LAST PATH I115
J 0
(-5852 4875);
DISPLAY 0.872340 (-5852 4875);
PAINT GREEN (-5852 4875);
DISPLAY INVISIBLE (-5852 4875);
FORCEADD TAP..1
(-5850 4925);
FORCEPROP 3 LASTPIN (-5900 4925) SIG_NAME M_J_CPU1_SA_DQ<23>
J 0
(-5890 4935);
DISPLAY 0.659574 (-5890 4935);
PAINT MONO (-5890 4935);
DISPLAY INVISIBLE (-5890 4935);
FORCEPROP 1 LASTPIN (-5900 4925) BN 23
J 0
(-5912 4933);
DISPLAY 0.489362 (-5912 4933);
PAINT GREEN (-5912 4933);
FORCEPROP 2 LAST CDS_LIB mstr_standard
J 0
(-5850 4925);
DISPLAY 0.723404 (-5850 4925);
PAINT MONO (-5850 4925);
DISPLAY INVISIBLE (-5850 4925);
FORCEPROP 1 LAST BODY_TYPE PLUMBING
J 0
(-5850 4975);
DISPLAY 0.872340 (-5850 4975);
PAINT GREEN (-5850 4975);
DISPLAY INVISIBLE (-5850 4975);
FORCEPROP 1 LAST HDL_TAP TRUE
J 0
(-5525 4800);
DISPLAY 0.872340 (-5525 4800);
DISPLAY INVISIBLE (-5525 4800);
FORCEPROP 1 LAST PATH I116
J 0
(-5852 4925);
DISPLAY 0.872340 (-5852 4925);
PAINT GREEN (-5852 4925);
DISPLAY INVISIBLE (-5852 4925);
FORCEADD TAP..1
(-5850 4975);
FORCEPROP 3 LASTPIN (-5900 4975) SIG_NAME M_J_CPU1_SA_DQ<24>
J 0
(-5890 4985);
DISPLAY 0.659574 (-5890 4985);
PAINT MONO (-5890 4985);
DISPLAY INVISIBLE (-5890 4985);
FORCEPROP 1 LASTPIN (-5900 4975) BN 24
J 0
(-5912 4983);
DISPLAY 0.489362 (-5912 4983);
PAINT GREEN (-5912 4983);
FORCEPROP 2 LAST CDS_LIB mstr_standard
J 0
(-5850 4975);
DISPLAY 0.723404 (-5850 4975);
PAINT MONO (-5850 4975);
DISPLAY INVISIBLE (-5850 4975);
FORCEPROP 1 LAST BODY_TYPE PLUMBING
J 0
(-5850 5025);
DISPLAY 0.872340 (-5850 5025);
PAINT GREEN (-5850 5025);
DISPLAY INVISIBLE (-5850 5025);
FORCEPROP 1 LAST HDL_TAP TRUE
J 0
(-5525 4850);
DISPLAY 0.872340 (-5525 4850);
DISPLAY INVISIBLE (-5525 4850);
FORCEPROP 1 LAST PATH I117
J 0
(-5852 4975);
DISPLAY 0.872340 (-5852 4975);
PAINT GREEN (-5852 4975);
DISPLAY INVISIBLE (-5852 4975);
FORCEADD TAP..1
(-5850 5025);
FORCEPROP 3 LASTPIN (-5900 5025) SIG_NAME M_J_CPU1_SA_DQ<25>
J 0
(-5890 5035);
DISPLAY 0.659574 (-5890 5035);
PAINT MONO (-5890 5035);
DISPLAY INVISIBLE (-5890 5035);
FORCEPROP 1 LASTPIN (-5900 5025) BN 25
J 0
(-5912 5033);
DISPLAY 0.489362 (-5912 5033);
PAINT GREEN (-5912 5033);
FORCEPROP 2 LAST CDS_LIB mstr_standard
J 0
(-5850 5025);
DISPLAY 0.723404 (-5850 5025);
PAINT MONO (-5850 5025);
DISPLAY INVISIBLE (-5850 5025);
FORCEPROP 1 LAST BODY_TYPE PLUMBING
J 0
(-5850 5075);
DISPLAY 0.872340 (-5850 5075);
PAINT GREEN (-5850 5075);
DISPLAY INVISIBLE (-5850 5075);
FORCEPROP 1 LAST HDL_TAP TRUE
J 0
(-5525 4900);
DISPLAY 0.872340 (-5525 4900);
DISPLAY INVISIBLE (-5525 4900);
FORCEPROP 1 LAST PATH I118
J 0
(-5852 5025);
DISPLAY 0.872340 (-5852 5025);
PAINT GREEN (-5852 5025);
DISPLAY INVISIBLE (-5852 5025);
FORCEADD TAP..1
(-5850 5075);
FORCEPROP 3 LASTPIN (-5900 5075) SIG_NAME M_J_CPU1_SA_DQ<26>
J 0
(-5890 5085);
DISPLAY 0.659574 (-5890 5085);
PAINT MONO (-5890 5085);
DISPLAY INVISIBLE (-5890 5085);
FORCEPROP 1 LASTPIN (-5900 5075) BN 26
J 0
(-5912 5083);
DISPLAY 0.489362 (-5912 5083);
PAINT GREEN (-5912 5083);
FORCEPROP 2 LAST CDS_LIB mstr_standard
J 0
(-5850 5075);
DISPLAY 0.723404 (-5850 5075);
PAINT MONO (-5850 5075);
DISPLAY INVISIBLE (-5850 5075);
FORCEPROP 1 LAST BODY_TYPE PLUMBING
J 0
(-5850 5125);
DISPLAY 0.872340 (-5850 5125);
PAINT GREEN (-5850 5125);
DISPLAY INVISIBLE (-5850 5125);
FORCEPROP 1 LAST HDL_TAP TRUE
J 0
(-5525 4950);
DISPLAY 0.872340 (-5525 4950);
DISPLAY INVISIBLE (-5525 4950);
FORCEPROP 1 LAST PATH I119
J 0
(-5852 5075);
DISPLAY 0.872340 (-5852 5075);
PAINT GREEN (-5852 5075);
DISPLAY INVISIBLE (-5852 5075);
FORCEADD OFFPAGE..1
(-8150 4025);
FORCEPROP 2 LAST $XR0 46 
J 0
(-8401 4025);
DISPLAY 0.638298 (-8401 4025);
PAINT MONO (-8401 4025);
FORCEPROP 2 LAST CDS_LIB mstr_standard
J 0
(-8150 4025);
DISPLAY 0.808511 (-8150 4025);
DISPLAY INVISIBLE (-8150 4025);
FORCEPROP 1 LAST OFFPAGE TRUE
J 0
(-7825 3900);
DISPLAY 0.872340 (-7825 3900);
PAINT GREEN (-7825 3900);
DISPLAY INVISIBLE (-7825 3900);
FORCEPROP 1 LAST COMMENT_BODY TRUE
J 0
(-8025 3925);
DISPLAY 0.872340 (-8025 3925);
PAINT GREEN (-8025 3925);
DISPLAY INVISIBLE (-8025 3925);
FORCEPROP 2 LAST PATH I12
J 0
(-8400 4075);
DISPLAY 1.021277 (-8400 4075);
DISPLAY INVISIBLE (-8400 4075);
FORCEADD TAP..1
(-5850 5125);
FORCEPROP 3 LASTPIN (-5900 5125) SIG_NAME M_J_CPU1_SA_DQ<27>
J 0
(-5890 5135);
DISPLAY 0.659574 (-5890 5135);
PAINT MONO (-5890 5135);
DISPLAY INVISIBLE (-5890 5135);
FORCEPROP 1 LASTPIN (-5900 5125) BN 27
J 0
(-5912 5133);
DISPLAY 0.489362 (-5912 5133);
PAINT GREEN (-5912 5133);
FORCEPROP 2 LAST CDS_LIB mstr_standard
J 0
(-5850 5125);
DISPLAY 0.723404 (-5850 5125);
PAINT MONO (-5850 5125);
DISPLAY INVISIBLE (-5850 5125);
FORCEPROP 1 LAST BODY_TYPE PLUMBING
J 0
(-5850 5175);
DISPLAY 0.872340 (-5850 5175);
PAINT GREEN (-5850 5175);
DISPLAY INVISIBLE (-5850 5175);
FORCEPROP 1 LAST HDL_TAP TRUE
J 0
(-5525 5000);
DISPLAY 0.872340 (-5525 5000);
DISPLAY INVISIBLE (-5525 5000);
FORCEPROP 1 LAST PATH I120
J 0
(-5852 5125);
DISPLAY 0.872340 (-5852 5125);
PAINT GREEN (-5852 5125);
DISPLAY INVISIBLE (-5852 5125);
FORCEADD TAP..1
(-5850 5175);
FORCEPROP 3 LASTPIN (-5900 5175) SIG_NAME M_J_CPU1_SA_DQ<28>
J 0
(-5890 5185);
DISPLAY 0.659574 (-5890 5185);
PAINT MONO (-5890 5185);
DISPLAY INVISIBLE (-5890 5185);
FORCEPROP 1 LASTPIN (-5900 5175) BN 28
J 0
(-5912 5183);
DISPLAY 0.489362 (-5912 5183);
PAINT GREEN (-5912 5183);
FORCEPROP 2 LAST CDS_LIB mstr_standard
J 0
(-5850 5175);
DISPLAY 0.723404 (-5850 5175);
PAINT MONO (-5850 5175);
DISPLAY INVISIBLE (-5850 5175);
FORCEPROP 1 LAST BODY_TYPE PLUMBING
J 0
(-5850 5225);
DISPLAY 0.872340 (-5850 5225);
PAINT GREEN (-5850 5225);
DISPLAY INVISIBLE (-5850 5225);
FORCEPROP 1 LAST HDL_TAP TRUE
J 0
(-5525 5050);
DISPLAY 0.872340 (-5525 5050);
DISPLAY INVISIBLE (-5525 5050);
FORCEPROP 1 LAST PATH I121
J 0
(-5852 5175);
DISPLAY 0.872340 (-5852 5175);
PAINT GREEN (-5852 5175);
DISPLAY INVISIBLE (-5852 5175);
FORCEADD TAP..1
(-5850 5275);
FORCEPROP 3 LASTPIN (-5900 5275) SIG_NAME M_J_CPU1_SA_DQ<30>
J 0
(-5890 5285);
DISPLAY 0.659574 (-5890 5285);
PAINT MONO (-5890 5285);
DISPLAY INVISIBLE (-5890 5285);
FORCEPROP 1 LASTPIN (-5900 5275) BN 30
J 0
(-5912 5283);
DISPLAY 0.489362 (-5912 5283);
PAINT GREEN (-5912 5283);
FORCEPROP 2 LAST CDS_LIB mstr_standard
J 0
(-5850 5275);
DISPLAY 0.723404 (-5850 5275);
PAINT MONO (-5850 5275);
DISPLAY INVISIBLE (-5850 5275);
FORCEPROP 1 LAST BODY_TYPE PLUMBING
J 0
(-5850 5325);
DISPLAY 0.872340 (-5850 5325);
PAINT GREEN (-5850 5325);
DISPLAY INVISIBLE (-5850 5325);
FORCEPROP 1 LAST HDL_TAP TRUE
J 0
(-5525 5150);
DISPLAY 0.872340 (-5525 5150);
DISPLAY INVISIBLE (-5525 5150);
FORCEPROP 1 LAST PATH I122
J 0
(-5852 5275);
DISPLAY 0.872340 (-5852 5275);
PAINT GREEN (-5852 5275);
DISPLAY INVISIBLE (-5852 5275);
FORCEADD TAP..1
(-5850 5225);
FORCEPROP 3 LASTPIN (-5900 5225) SIG_NAME M_J_CPU1_SA_DQ<29>
J 0
(-5890 5235);
DISPLAY 0.659574 (-5890 5235);
PAINT MONO (-5890 5235);
DISPLAY INVISIBLE (-5890 5235);
FORCEPROP 1 LASTPIN (-5900 5225) BN 29
J 0
(-5912 5233);
DISPLAY 0.489362 (-5912 5233);
PAINT GREEN (-5912 5233);
FORCEPROP 2 LAST CDS_LIB mstr_standard
J 0
(-5850 5225);
DISPLAY 0.723404 (-5850 5225);
PAINT MONO (-5850 5225);
DISPLAY INVISIBLE (-5850 5225);
FORCEPROP 1 LAST BODY_TYPE PLUMBING
J 0
(-5850 5275);
DISPLAY 0.872340 (-5850 5275);
PAINT GREEN (-5850 5275);
DISPLAY INVISIBLE (-5850 5275);
FORCEPROP 1 LAST HDL_TAP TRUE
J 0
(-5525 5100);
DISPLAY 0.872340 (-5525 5100);
DISPLAY INVISIBLE (-5525 5100);
FORCEPROP 1 LAST PATH I123
J 0
(-5852 5225);
DISPLAY 0.872340 (-5852 5225);
PAINT GREEN (-5852 5225);
DISPLAY INVISIBLE (-5852 5225);
FORCEADD TAP..1
(-5850 5325);
FORCEPROP 3 LASTPIN (-5900 5325) SIG_NAME M_J_CPU1_SA_DQ<31>
J 0
(-5890 5335);
DISPLAY 0.659574 (-5890 5335);
PAINT MONO (-5890 5335);
DISPLAY INVISIBLE (-5890 5335);
FORCEPROP 1 LASTPIN (-5900 5325) BN 31
J 0
(-5912 5333);
DISPLAY 0.489362 (-5912 5333);
PAINT GREEN (-5912 5333);
FORCEPROP 2 LAST CDS_LIB mstr_standard
J 0
(-5850 5325);
DISPLAY 0.723404 (-5850 5325);
PAINT MONO (-5850 5325);
DISPLAY INVISIBLE (-5850 5325);
FORCEPROP 1 LAST BODY_TYPE PLUMBING
J 0
(-5850 5375);
DISPLAY 0.872340 (-5850 5375);
PAINT GREEN (-5850 5375);
DISPLAY INVISIBLE (-5850 5375);
FORCEPROP 1 LAST HDL_TAP TRUE
J 0
(-5525 5200);
DISPLAY 0.872340 (-5525 5200);
DISPLAY INVISIBLE (-5525 5200);
FORCEPROP 1 LAST PATH I124
J 0
(-5852 5325);
DISPLAY 0.872340 (-5852 5325);
PAINT GREEN (-5852 5325);
DISPLAY INVISIBLE (-5852 5325);
FORCEADD OFFPAGE..3
(-5200 5375);
FORCEPROP 2 LAST $XR0 46 
J 0
(-4986 5375);
DISPLAY 0.638298 (-4986 5375);
PAINT MONO (-4986 5375);
FORCEPROP 2 LAST CDS_LIB mstr_standard
J 0
(-5200 5375);
DISPLAY 0.723404 (-5200 5375);
PAINT MONO (-5200 5375);
DISPLAY INVISIBLE (-5200 5375);
FORCEPROP 1 LAST OFFPAGE TRUE
J 0
(-4875 5250);
DISPLAY 0.872340 (-4875 5250);
PAINT GREEN (-4875 5250);
DISPLAY INVISIBLE (-4875 5250);
FORCEPROP 1 LAST COMMENT_BODY TRUE
J 0
(-5250 5275);
DISPLAY 0.872340 (-5250 5275);
PAINT GREEN (-5250 5275);
DISPLAY INVISIBLE (-5250 5275);
FORCEPROP 2 LAST PATH I125
J 0
(-4975 5425);
DISPLAY 1.021277 (-4975 5425);
DISPLAY INVISIBLE (-4975 5425);
FORCEADD GND..1
(-6250 950);
FORCEPROP 3 LASTPIN (-6250 1000) SIG_NAME GND\g
J 0
(-6240 1010);
DISPLAY 0.659574 (-6240 1010);
PAINT MONO (-6240 1010);
DISPLAY INVISIBLE (-6240 1010);
FORCEPROP 1 LAST VOLTAGE 0.0
J 0
(-6295 907);
DISPLAY 0.723404 (-6295 907);
PAINT SKYBLUE (-6295 907);
DISPLAY INVISIBLE (-6295 907);
FORCEPROP 2 LAST CDS_LIB mstr_symbols
J 0
(-6250 950);
DISPLAY 0.808511 (-6250 950);
DISPLAY INVISIBLE (-6250 950);
FORCEPROP 2 LAST BOM_COST MEM
J 0
(-6350 1025);
DISPLAY 0.808511 (-6350 1025);
DISPLAY INVISIBLE (-6350 1025);
FORCEPROP 1 LAST SIZE 1B
J 0
(-6175 900);
DISPLAY 0.851064 (-6175 900);
PAINT GREEN (-6175 900);
DISPLAY INVISIBLE (-6175 900);
FORCEPROP 1 LAST BODY_TYPE PLUMBING
J 0
(-6295 907);
DISPLAY 0.340426 (-6295 907);
PAINT GREEN (-6295 907);
DISPLAY INVISIBLE (-6295 907);
FORCEPROP 1 LAST HDL_POWER GND
J 0
(-6250 1100);
DISPLAY 0.851064 (-6250 1100);
PAINT GREEN (-6250 1100);
DISPLAY INVISIBLE (-6250 1100);
FORCEPROP 1 LAST PATH I126
J 0
(-6175 950);
DISPLAY 0.872340 (-6175 950);
PAINT AQUA (-6175 950);
DISPLAY INVISIBLE (-6175 950);
FORCEADD Q_RES..2
(-6250 1175);
FORCEPROP 1 LAST LOCATION R776
J 0
(-6205 1300);
DISPLAY 0.489362 (-6205 1300);
PAINT SKYBLUE (-6205 1300);
FORCEPROP 0 LAST $SEC 1
J 0
(-6200 1350);
DISPLAY 0.680851 (-6200 1350);
PAINT MONO (-6200 1350);
DISPLAY INVISIBLE (-6200 1350);
FORCEPROP 0 LAST CDS_SEC 1
J 0
(-6200 1350);
DISPLAY 1.021277 (-6200 1350);
DISPLAY INVISIBLE (-6200 1350);
FORCEPROP 1 LASTPIN (-6250 1275) $PN 1
J 0
(-6245 1237);
DISPLAY 0.489362 (-6245 1237);
PAINT MONO (-6245 1237);
FORCEPROP 1 LASTPIN (-6250 1075) $PN 2
J 0
(-6245 1085);
DISPLAY 0.489362 (-6245 1085);
PAINT MONO (-6245 1085);
FORCEPROP 1 LAST PACK_TYPE 0402LF
J 0
(-6210 1000);
DISPLAY 0.489362 (-6210 1000);
PAINT SKYBLUE (-6210 1000);
FORCEPROP 1 LAST VALUE 35.7K
J 0
(-6205 1250);
DISPLAY 0.489362 (-6205 1250);
PAINT SKYBLUE (-6205 1250);
FORCEPROP 1 LAST TOLERANCE 1%
J 0
(-6205 1200);
DISPLAY 0.489362 (-6205 1200);
PAINT SKYBLUE (-6205 1200);
FORCEPROP 1 LAST MATERIAL CHIP
J 0
(-6210 1100);
DISPLAY 0.489362 (-6210 1100);
PAINT SKYBLUE (-6210 1100);
FORCEPROP 1 LAST WATTAGE 1/16W
J 0
(-6210 1150);
DISPLAY 0.489362 (-6210 1150);
PAINT SKYBLUE (-6210 1150);
FORCEPROP 2 LAST CDS_LIB pure_quanta
J 0
(-6250 1175);
DISPLAY INVISIBLE (-6250 1175);
FORCEPROP 1 LAST PATH I127
J 0
(-6200 1350);
DISPLAY 0.978723 (-6200 1350);
PAINT WHITE (-6200 1350);
DISPLAY INVISIBLE (-6200 1350);
FORCEPROP 1 LAST PART_NUMBER CS33572FB01
J 0
(-6210 1050);
DISPLAY 0.489362 (-6210 1050);
PAINT SKYBLUE (-6210 1050);
DISPLAY INVISIBLE (-6210 1050);
FORCEADD GND..1
(-2025 1800);
FORCEPROP 3 LASTPIN (-2025 1850) SIG_NAME GND\g
J 0
(-2015 1860);
DISPLAY 0.659574 (-2015 1860);
PAINT MONO (-2015 1860);
DISPLAY INVISIBLE (-2015 1860);
FORCEPROP 1 LAST VOLTAGE 0.0
J 0
(-2070 1757);
DISPLAY 0.723404 (-2070 1757);
PAINT SKYBLUE (-2070 1757);
DISPLAY INVISIBLE (-2070 1757);
FORCEPROP 1 LAST SIZE 1B
J 0
(-1950 1750);
DISPLAY 0.851064 (-1950 1750);
PAINT GREEN (-1950 1750);
DISPLAY INVISIBLE (-1950 1750);
FORCEPROP 2 LAST CDS_LIB mstr_symbols
J 0
(-2025 1800);
DISPLAY 0.723404 (-2025 1800);
DISPLAY INVISIBLE (-2025 1800);
FORCEPROP 1 LAST BODY_TYPE PLUMBING
J 0
(-2070 1757);
DISPLAY 0.340426 (-2070 1757);
PAINT GREEN (-2070 1757);
DISPLAY INVISIBLE (-2070 1757);
FORCEPROP 1 LAST HDL_POWER GND
J 0
(-2025 1950);
DISPLAY 0.851064 (-2025 1950);
PAINT GREEN (-2025 1950);
DISPLAY INVISIBLE (-2025 1950);
FORCEPROP 1 LAST PATH I128
J 0
(-1950 1800);
DISPLAY 0.872340 (-1950 1800);
PAINT AQUA (-1950 1800);
DISPLAY INVISIBLE (-1950 1800);
FORCEADD OFFPAGE..5
(-7025 1350);
FORCEPROP 2 LAST $XR0 107 
J 0
(-7280 1350);
DISPLAY 0.638298 (-7280 1350);
PAINT MONO (-7280 1350);
FORCEPROP 2 LAST CDS_LIB mstr_standard
J 0
(-7025 1350);
DISPLAY 0.808511 (-7025 1350);
DISPLAY INVISIBLE (-7025 1350);
FORCEPROP 2 LAST BOM_COST MEM
J 0
(-7100 1425);
DISPLAY 0.808511 (-7100 1425);
DISPLAY INVISIBLE (-7100 1425);
FORCEPROP 1 LAST OFFPAGE TRUE
J 0
(-6700 1225);
DISPLAY 0.872340 (-6700 1225);
PAINT GREEN (-6700 1225);
DISPLAY INVISIBLE (-6700 1225);
FORCEPROP 1 LAST COMMENT_BODY TRUE
J 0
(-6925 1275);
DISPLAY 0.872340 (-6925 1275);
PAINT GREEN (-6925 1275);
DISPLAY INVISIBLE (-6925 1275);
FORCEPROP 2 LAST PATH I129
J 0
(-7275 1400);
DISPLAY 1.021277 (-7275 1400);
DISPLAY INVISIBLE (-7275 1400);
FORCEADD OFFPAGE..1
(-8150 4075);
FORCEPROP 2 LAST $XR0 46 
J 0
(-8401 4075);
DISPLAY 0.638298 (-8401 4075);
PAINT MONO (-8401 4075);
FORCEPROP 2 LAST CDS_LIB mstr_standard
J 0
(-8150 4075);
DISPLAY 0.723404 (-8150 4075);
PAINT MONO (-8150 4075);
DISPLAY INVISIBLE (-8150 4075);
FORCEPROP 1 LAST OFFPAGE TRUE
J 0
(-7825 3950);
DISPLAY 0.872340 (-7825 3950);
PAINT GREEN (-7825 3950);
DISPLAY INVISIBLE (-7825 3950);
FORCEPROP 1 LAST COMMENT_BODY TRUE
J 0
(-8025 3975);
DISPLAY 0.872340 (-8025 3975);
PAINT GREEN (-8025 3975);
DISPLAY INVISIBLE (-8025 3975);
FORCEPROP 2 LAST PATH I13
J 0
(-8400 4125);
DISPLAY 1.021277 (-8400 4125);
DISPLAY INVISIBLE (-8400 4125);
FORCEADD OFFPAGE..1
(-8150 4325);
FORCEPROP 2 LAST $XR0 46 
J 0
(-8401 4325);
DISPLAY 0.638298 (-8401 4325);
PAINT MONO (-8401 4325);
FORCEPROP 2 LAST CDS_LIB mstr_standard
J 0
(-8150 4325);
DISPLAY 0.808511 (-8150 4325);
DISPLAY INVISIBLE (-8150 4325);
FORCEPROP 1 LAST OFFPAGE TRUE
J 0
(-7825 4200);
DISPLAY 0.872340 (-7825 4200);
PAINT GREEN (-7825 4200);
DISPLAY INVISIBLE (-7825 4200);
FORCEPROP 1 LAST COMMENT_BODY TRUE
J 0
(-8025 4225);
DISPLAY 0.872340 (-8025 4225);
PAINT GREEN (-8025 4225);
DISPLAY INVISIBLE (-8025 4225);
FORCEPROP 2 LAST PATH I14
J 0
(-8400 4375);
DISPLAY 1.021277 (-8400 4375);
DISPLAY INVISIBLE (-8400 4375);
FORCEADD GND..1
(-225 1575);
FORCEPROP 3 LASTPIN (-225 1625) SIG_NAME GND\g
J 0
(-215 1635);
DISPLAY 0.659574 (-215 1635);
PAINT MONO (-215 1635);
DISPLAY INVISIBLE (-215 1635);
FORCEPROP 1 LAST VOLTAGE 0.0
J 0
(-270 1532);
DISPLAY 0.723404 (-270 1532);
PAINT SKYBLUE (-270 1532);
DISPLAY INVISIBLE (-270 1532);
FORCEPROP 1 LAST SIZE 1B
J 0
(-150 1525);
DISPLAY 0.851064 (-150 1525);
PAINT GREEN (-150 1525);
DISPLAY INVISIBLE (-150 1525);
FORCEPROP 2 LAST CDS_LIB mstr_symbols
J 0
(-225 1575);
DISPLAY 0.723404 (-225 1575);
DISPLAY INVISIBLE (-225 1575);
FORCEPROP 1 LAST BODY_TYPE PLUMBING
J 0
(-270 1532);
DISPLAY 0.340426 (-270 1532);
PAINT GREEN (-270 1532);
DISPLAY INVISIBLE (-270 1532);
FORCEPROP 1 LAST HDL_POWER GND
J 0
(-225 1725);
DISPLAY 0.851064 (-225 1725);
PAINT GREEN (-225 1725);
DISPLAY INVISIBLE (-225 1725);
FORCEPROP 1 LAST PATH I142
J 0
(-150 1575);
DISPLAY 0.872340 (-150 1575);
PAINT AQUA (-150 1575);
DISPLAY INVISIBLE (-150 1575);
FORCEADD SCONN288_DDR506112002KQ..3
(-1125 3575);
FORCEPROP 1 LAST LOCATION J29
J 0
(-1575 5550);
DISPLAY 0.468085 (-1575 5550);
PAINT SKYBLUE (-1575 5550);
FORCEPROP 0 LAST $SEC 3
J 0
(-1575 5700);
DISPLAY 0.680851 (-1575 5700);
PAINT MONO (-1575 5700);
DISPLAY INVISIBLE (-1575 5700);
FORCEPROP 2 LAST CDS_SEC 3
J 0
(-1575 5700);
DISPLAY 1.021277 (-1575 5700);
DISPLAY INVISIBLE (-1575 5700);
FORCEPROP 0 LASTPIN (-525 1975) $PN G1
J 0
(-515 1985);
DISPLAY 0.680851 (-515 1985);
PAINT MONO (-515 1985);
FORCEPROP 0 LASTPIN (-525 1925) $PN G2
J 0
(-515 1935);
DISPLAY 0.680851 (-515 1935);
PAINT MONO (-515 1935);
FORCEPROP 0 LASTPIN (-525 1875) $PN G3
J 0
(-515 1885);
DISPLAY 0.680851 (-515 1885);
PAINT MONO (-515 1885);
FORCEPROP 0 LASTPIN (-1725 5125) $PN 1
J 2
(-1735 5135);
DISPLAY 0.680851 (-1735 5135);
PAINT MONO (-1735 5135);
FORCEPROP 0 LASTPIN (-1725 5175) $PN 145
J 2
(-1735 5185);
DISPLAY 0.680851 (-1735 5185);
PAINT MONO (-1735 5185);
FORCEPROP 0 LASTPIN (-1725 5225) $PN 146
J 2
(-1735 5235);
DISPLAY 0.680851 (-1735 5235);
PAINT MONO (-1735 5235);
FORCEPROP 0 LASTPIN (-525 2075) $PN 6
J 0
(-515 2085);
DISPLAY 0.680851 (-515 2085);
PAINT MONO (-515 2085);
FORCEPROP 0 LASTPIN (-525 2125) $PN 8
J 0
(-515 2135);
DISPLAY 0.680851 (-515 2135);
PAINT MONO (-515 2135);
FORCEPROP 0 LASTPIN (-525 2175) $PN 10
J 0
(-515 2185);
DISPLAY 0.680851 (-515 2185);
PAINT MONO (-515 2185);
FORCEPROP 0 LASTPIN (-525 2225) $PN 13
J 0
(-515 2235);
DISPLAY 0.680851 (-515 2235);
PAINT MONO (-515 2235);
FORCEPROP 0 LASTPIN (-525 2275) $PN 15
J 0
(-515 2285);
DISPLAY 0.680851 (-515 2285);
PAINT MONO (-515 2285);
FORCEPROP 0 LASTPIN (-525 2325) $PN 17
J 0
(-515 2335);
DISPLAY 0.680851 (-515 2335);
PAINT MONO (-515 2335);
FORCEPROP 0 LASTPIN (-525 2375) $PN 19
J 0
(-515 2385);
DISPLAY 0.680851 (-515 2385);
PAINT MONO (-515 2385);
FORCEPROP 0 LASTPIN (-525 2425) $PN 21
J 0
(-515 2435);
DISPLAY 0.680851 (-515 2435);
PAINT MONO (-515 2435);
FORCEPROP 0 LASTPIN (-525 2475) $PN 24
J 0
(-515 2485);
DISPLAY 0.680851 (-515 2485);
PAINT MONO (-515 2485);
FORCEPROP 0 LASTPIN (-525 2525) $PN 26
J 0
(-515 2535);
DISPLAY 0.680851 (-515 2535);
PAINT MONO (-515 2535);
FORCEPROP 0 LASTPIN (-525 2575) $PN 28
J 0
(-515 2585);
DISPLAY 0.680851 (-515 2585);
PAINT MONO (-515 2585);
FORCEPROP 0 LASTPIN (-525 2625) $PN 30
J 0
(-515 2635);
DISPLAY 0.680851 (-515 2635);
PAINT MONO (-515 2635);
FORCEPROP 0 LASTPIN (-525 2675) $PN 32
J 0
(-515 2685);
DISPLAY 0.680851 (-515 2685);
PAINT MONO (-515 2685);
FORCEPROP 0 LASTPIN (-525 2725) $PN 35
J 0
(-515 2735);
DISPLAY 0.680851 (-515 2735);
PAINT MONO (-515 2735);
FORCEPROP 0 LASTPIN (-525 2775) $PN 37
J 0
(-515 2785);
DISPLAY 0.680851 (-515 2785);
PAINT MONO (-515 2785);
FORCEPROP 0 LASTPIN (-525 2825) $PN 39
J 0
(-515 2835);
DISPLAY 0.680851 (-515 2835);
PAINT MONO (-515 2835);
FORCEPROP 0 LASTPIN (-525 2875) $PN 41
J 0
(-515 2885);
DISPLAY 0.680851 (-515 2885);
PAINT MONO (-515 2885);
FORCEPROP 0 LASTPIN (-525 2925) $PN 43
J 0
(-515 2935);
DISPLAY 0.680851 (-515 2935);
PAINT MONO (-515 2935);
FORCEPROP 0 LASTPIN (-525 2975) $PN 46
J 0
(-515 2985);
DISPLAY 0.680851 (-515 2985);
PAINT MONO (-515 2985);
FORCEPROP 0 LASTPIN (-525 3025) $PN 48
J 0
(-515 3035);
DISPLAY 0.680851 (-515 3035);
PAINT MONO (-515 3035);
FORCEPROP 0 LASTPIN (-525 3075) $PN 50
J 0
(-515 3085);
DISPLAY 0.680851 (-515 3085);
PAINT MONO (-515 3085);
FORCEPROP 0 LASTPIN (-525 3125) $PN 52
J 0
(-515 3135);
DISPLAY 0.680851 (-515 3135);
PAINT MONO (-515 3135);
FORCEPROP 0 LASTPIN (-525 3175) $PN 54
J 0
(-515 3185);
DISPLAY 0.680851 (-515 3185);
PAINT MONO (-515 3185);
FORCEPROP 0 LASTPIN (-525 3225) $PN 57
J 0
(-515 3235);
DISPLAY 0.680851 (-515 3235);
PAINT MONO (-515 3235);
FORCEPROP 0 LASTPIN (-525 3275) $PN 59
J 0
(-515 3285);
DISPLAY 0.680851 (-515 3285);
PAINT MONO (-515 3285);
FORCEPROP 0 LASTPIN (-525 3325) $PN 61
J 0
(-515 3335);
DISPLAY 0.680851 (-515 3335);
PAINT MONO (-515 3335);
FORCEPROP 0 LASTPIN (-525 3375) $PN 63
J 0
(-515 3385);
DISPLAY 0.680851 (-515 3385);
PAINT MONO (-515 3385);
FORCEPROP 0 LASTPIN (-525 3425) $PN 65
J 0
(-515 3435);
DISPLAY 0.680851 (-515 3435);
PAINT MONO (-515 3435);
FORCEPROP 0 LASTPIN (-525 3475) $PN 67
J 0
(-515 3485);
DISPLAY 0.680851 (-515 3485);
PAINT MONO (-515 3485);
FORCEPROP 0 LASTPIN (-525 3525) $PN 69
J 0
(-515 3535);
DISPLAY 0.680851 (-515 3535);
PAINT MONO (-515 3535);
FORCEPROP 0 LASTPIN (-525 3575) $PN 71
J 0
(-515 3585);
DISPLAY 0.680851 (-515 3585);
PAINT MONO (-515 3585);
FORCEPROP 0 LASTPIN (-525 3625) $PN 73
J 0
(-515 3635);
DISPLAY 0.680851 (-515 3635);
PAINT MONO (-515 3635);
FORCEPROP 0 LASTPIN (-525 3675) $PN 75
J 0
(-515 3685);
DISPLAY 0.680851 (-515 3685);
PAINT MONO (-515 3685);
FORCEPROP 0 LASTPIN (-525 3725) $PN 77
J 0
(-515 3735);
DISPLAY 0.680851 (-515 3735);
PAINT MONO (-515 3735);
FORCEPROP 0 LASTPIN (-525 3775) $PN 79
J 0
(-515 3785);
DISPLAY 0.680851 (-515 3785);
PAINT MONO (-515 3785);
FORCEPROP 0 LASTPIN (-525 3825) $PN 81
J 0
(-515 3835);
DISPLAY 0.680851 (-515 3835);
PAINT MONO (-515 3835);
FORCEPROP 0 LASTPIN (-525 3875) $PN 83
J 0
(-515 3885);
DISPLAY 0.680851 (-515 3885);
PAINT MONO (-515 3885);
FORCEPROP 0 LASTPIN (-525 3925) $PN 85
J 0
(-515 3935);
DISPLAY 0.680851 (-515 3935);
PAINT MONO (-515 3935);
FORCEPROP 0 LASTPIN (-525 3975) $PN 88
J 0
(-515 3985);
DISPLAY 0.680851 (-515 3985);
PAINT MONO (-515 3985);
FORCEPROP 0 LASTPIN (-525 4025) $PN 90
J 0
(-515 4035);
DISPLAY 0.680851 (-515 4035);
PAINT MONO (-515 4035);
FORCEPROP 0 LASTPIN (-525 4075) $PN 92
J 0
(-515 4085);
DISPLAY 0.680851 (-515 4085);
PAINT MONO (-515 4085);
FORCEPROP 0 LASTPIN (-525 4125) $PN 95
J 0
(-515 4135);
DISPLAY 0.680851 (-515 4135);
PAINT MONO (-515 4135);
FORCEPROP 0 LASTPIN (-525 4175) $PN 97
J 0
(-515 4185);
DISPLAY 0.680851 (-515 4185);
PAINT MONO (-515 4185);
FORCEPROP 0 LASTPIN (-525 4225) $PN 99
J 0
(-515 4235);
DISPLAY 0.680851 (-515 4235);
PAINT MONO (-515 4235);
FORCEPROP 0 LASTPIN (-525 4275) $PN 101
J 0
(-515 4285);
DISPLAY 0.680851 (-515 4285);
PAINT MONO (-515 4285);
FORCEPROP 0 LASTPIN (-525 4325) $PN 103
J 0
(-515 4335);
DISPLAY 0.680851 (-515 4335);
PAINT MONO (-515 4335);
FORCEPROP 0 LASTPIN (-525 4375) $PN 106
J 0
(-515 4385);
DISPLAY 0.680851 (-515 4385);
PAINT MONO (-515 4385);
FORCEPROP 0 LASTPIN (-525 4425) $PN 108
J 0
(-515 4435);
DISPLAY 0.680851 (-515 4435);
PAINT MONO (-515 4435);
FORCEPROP 0 LASTPIN (-525 4475) $PN 110
J 0
(-515 4485);
DISPLAY 0.680851 (-515 4485);
PAINT MONO (-515 4485);
FORCEPROP 0 LASTPIN (-525 4525) $PN 112
J 0
(-515 4535);
DISPLAY 0.680851 (-515 4535);
PAINT MONO (-515 4535);
FORCEPROP 0 LASTPIN (-525 4575) $PN 114
J 0
(-515 4585);
DISPLAY 0.680851 (-515 4585);
PAINT MONO (-515 4585);
FORCEPROP 0 LASTPIN (-525 4625) $PN 117
J 0
(-515 4635);
DISPLAY 0.680851 (-515 4635);
PAINT MONO (-515 4635);
FORCEPROP 0 LASTPIN (-525 4675) $PN 119
J 0
(-515 4685);
DISPLAY 0.680851 (-515 4685);
PAINT MONO (-515 4685);
FORCEPROP 0 LASTPIN (-525 4725) $PN 121
J 0
(-515 4735);
DISPLAY 0.680851 (-515 4735);
PAINT MONO (-515 4735);
FORCEPROP 0 LASTPIN (-525 4775) $PN 123
J 0
(-515 4785);
DISPLAY 0.680851 (-515 4785);
PAINT MONO (-515 4785);
FORCEPROP 0 LASTPIN (-525 4825) $PN 125
J 0
(-515 4835);
DISPLAY 0.680851 (-515 4835);
PAINT MONO (-515 4835);
FORCEPROP 0 LASTPIN (-525 4875) $PN 128
J 0
(-515 4885);
DISPLAY 0.680851 (-515 4885);
PAINT MONO (-515 4885);
FORCEPROP 0 LASTPIN (-525 4925) $PN 130
J 0
(-515 4935);
DISPLAY 0.680851 (-515 4935);
PAINT MONO (-515 4935);
FORCEPROP 0 LASTPIN (-525 4975) $PN 132
J 0
(-515 4985);
DISPLAY 0.680851 (-515 4985);
PAINT MONO (-515 4985);
FORCEPROP 0 LASTPIN (-525 5025) $PN 134
J 0
(-515 5035);
DISPLAY 0.680851 (-515 5035);
PAINT MONO (-515 5035);
FORCEPROP 0 LASTPIN (-525 5075) $PN 136
J 0
(-515 5085);
DISPLAY 0.680851 (-515 5085);
PAINT MONO (-515 5085);
FORCEPROP 0 LASTPIN (-525 5125) $PN 139
J 0
(-515 5135);
DISPLAY 0.680851 (-515 5135);
PAINT MONO (-515 5135);
FORCEPROP 0 LASTPIN (-525 5175) $PN 141
J 0
(-515 5185);
DISPLAY 0.680851 (-515 5185);
PAINT MONO (-515 5185);
FORCEPROP 0 LASTPIN (-525 5225) $PN 143
J 0
(-515 5235);
DISPLAY 0.680851 (-515 5235);
PAINT MONO (-515 5235);
FORCEPROP 0 LASTPIN (-1725 1975) $PN 151
J 2
(-1735 1985);
DISPLAY 0.680851 (-1735 1985);
PAINT MONO (-1735 1985);
FORCEPROP 0 LASTPIN (-1725 2025) $PN 153
J 2
(-1735 2035);
DISPLAY 0.680851 (-1735 2035);
PAINT MONO (-1735 2035);
FORCEPROP 0 LASTPIN (-1725 2075) $PN 155
J 2
(-1735 2085);
DISPLAY 0.680851 (-1735 2085);
PAINT MONO (-1735 2085);
FORCEPROP 0 LASTPIN (-1725 2125) $PN 158
J 2
(-1735 2135);
DISPLAY 0.680851 (-1735 2135);
PAINT MONO (-1735 2135);
FORCEPROP 0 LASTPIN (-1725 2175) $PN 160
J 2
(-1735 2185);
DISPLAY 0.680851 (-1735 2185);
PAINT MONO (-1735 2185);
FORCEPROP 0 LASTPIN (-1725 2225) $PN 162
J 2
(-1735 2235);
DISPLAY 0.680851 (-1735 2235);
PAINT MONO (-1735 2235);
FORCEPROP 0 LASTPIN (-1725 2275) $PN 164
J 2
(-1735 2285);
DISPLAY 0.680851 (-1735 2285);
PAINT MONO (-1735 2285);
FORCEPROP 0 LASTPIN (-1725 2325) $PN 166
J 2
(-1735 2335);
DISPLAY 0.680851 (-1735 2335);
PAINT MONO (-1735 2335);
FORCEPROP 0 LASTPIN (-1725 2375) $PN 169
J 2
(-1735 2385);
DISPLAY 0.680851 (-1735 2385);
PAINT MONO (-1735 2385);
FORCEPROP 0 LASTPIN (-1725 2425) $PN 171
J 2
(-1735 2435);
DISPLAY 0.680851 (-1735 2435);
PAINT MONO (-1735 2435);
FORCEPROP 0 LASTPIN (-1725 2475) $PN 173
J 2
(-1735 2485);
DISPLAY 0.680851 (-1735 2485);
PAINT MONO (-1735 2485);
FORCEPROP 0 LASTPIN (-1725 2525) $PN 175
J 2
(-1735 2535);
DISPLAY 0.680851 (-1735 2535);
PAINT MONO (-1735 2535);
FORCEPROP 0 LASTPIN (-1725 2575) $PN 177
J 2
(-1735 2585);
DISPLAY 0.680851 (-1735 2585);
PAINT MONO (-1735 2585);
FORCEPROP 0 LASTPIN (-1725 2625) $PN 180
J 2
(-1735 2635);
DISPLAY 0.680851 (-1735 2635);
PAINT MONO (-1735 2635);
FORCEPROP 0 LASTPIN (-1725 2675) $PN 182
J 2
(-1735 2685);
DISPLAY 0.680851 (-1735 2685);
PAINT MONO (-1735 2685);
FORCEPROP 0 LASTPIN (-1725 2725) $PN 184
J 2
(-1735 2735);
DISPLAY 0.680851 (-1735 2735);
PAINT MONO (-1735 2735);
FORCEPROP 0 LASTPIN (-1725 2775) $PN 186
J 2
(-1735 2785);
DISPLAY 0.680851 (-1735 2785);
PAINT MONO (-1735 2785);
FORCEPROP 0 LASTPIN (-1725 2825) $PN 188
J 2
(-1735 2835);
DISPLAY 0.680851 (-1735 2835);
PAINT MONO (-1735 2835);
FORCEPROP 0 LASTPIN (-1725 2875) $PN 191
J 2
(-1735 2885);
DISPLAY 0.680851 (-1735 2885);
PAINT MONO (-1735 2885);
FORCEPROP 0 LASTPIN (-1725 2925) $PN 193
J 2
(-1735 2935);
DISPLAY 0.680851 (-1735 2935);
PAINT MONO (-1735 2935);
FORCEPROP 0 LASTPIN (-1725 2975) $PN 195
J 2
(-1735 2985);
DISPLAY 0.680851 (-1735 2985);
PAINT MONO (-1735 2985);
FORCEPROP 0 LASTPIN (-1725 3025) $PN 197
J 2
(-1735 3035);
DISPLAY 0.680851 (-1735 3035);
PAINT MONO (-1735 3035);
FORCEPROP 0 LASTPIN (-1725 3075) $PN 199
J 2
(-1735 3085);
DISPLAY 0.680851 (-1735 3085);
PAINT MONO (-1735 3085);
FORCEPROP 0 LASTPIN (-1725 3125) $PN 202
J 2
(-1735 3135);
DISPLAY 0.680851 (-1735 3135);
PAINT MONO (-1735 3135);
FORCEPROP 0 LASTPIN (-1725 3175) $PN 204
J 2
(-1735 3185);
DISPLAY 0.680851 (-1735 3185);
PAINT MONO (-1735 3185);
FORCEPROP 0 LASTPIN (-1725 3225) $PN 206
J 2
(-1735 3235);
DISPLAY 0.680851 (-1735 3235);
PAINT MONO (-1735 3235);
FORCEPROP 0 LASTPIN (-1725 3275) $PN 208
J 2
(-1735 3285);
DISPLAY 0.680851 (-1735 3285);
PAINT MONO (-1735 3285);
FORCEPROP 0 LASTPIN (-1725 3325) $PN 210
J 2
(-1735 3335);
DISPLAY 0.680851 (-1735 3335);
PAINT MONO (-1735 3335);
FORCEPROP 0 LASTPIN (-1725 3375) $PN 212
J 2
(-1735 3385);
DISPLAY 0.680851 (-1735 3385);
PAINT MONO (-1735 3385);
FORCEPROP 0 LASTPIN (-1725 3425) $PN 214
J 2
(-1735 3435);
DISPLAY 0.680851 (-1735 3435);
PAINT MONO (-1735 3435);
FORCEPROP 0 LASTPIN (-1725 3475) $PN 216
J 2
(-1735 3485);
DISPLAY 0.680851 (-1735 3485);
PAINT MONO (-1735 3485);
FORCEPROP 0 LASTPIN (-1725 3525) $PN 219
J 2
(-1735 3535);
DISPLAY 0.680851 (-1735 3535);
PAINT MONO (-1735 3535);
FORCEPROP 0 LASTPIN (-1725 3575) $PN 222
J 2
(-1735 3585);
DISPLAY 0.680851 (-1735 3585);
PAINT MONO (-1735 3585);
FORCEPROP 0 LASTPIN (-1725 3625) $PN 224
J 2
(-1735 3635);
DISPLAY 0.680851 (-1735 3635);
PAINT MONO (-1735 3635);
FORCEPROP 0 LASTPIN (-1725 3675) $PN 226
J 2
(-1735 3685);
DISPLAY 0.680851 (-1735 3685);
PAINT MONO (-1735 3685);
FORCEPROP 0 LASTPIN (-1725 3725) $PN 228
J 2
(-1735 3735);
DISPLAY 0.680851 (-1735 3735);
PAINT MONO (-1735 3735);
FORCEPROP 0 LASTPIN (-1725 3775) $PN 230
J 2
(-1735 3785);
DISPLAY 0.680851 (-1735 3785);
PAINT MONO (-1735 3785);
FORCEPROP 0 LASTPIN (-1725 3825) $PN 233
J 2
(-1735 3835);
DISPLAY 0.680851 (-1735 3835);
PAINT MONO (-1735 3835);
FORCEPROP 0 LASTPIN (-1725 3875) $PN 235
J 2
(-1735 3885);
DISPLAY 0.680851 (-1735 3885);
PAINT MONO (-1735 3885);
FORCEPROP 0 LASTPIN (-1725 3925) $PN 237
J 2
(-1735 3935);
DISPLAY 0.680851 (-1735 3935);
PAINT MONO (-1735 3935);
FORCEPROP 0 LASTPIN (-1725 3975) $PN 240
J 2
(-1735 3985);
DISPLAY 0.680851 (-1735 3985);
PAINT MONO (-1735 3985);
FORCEPROP 0 LASTPIN (-1725 4025) $PN 242
J 2
(-1735 4035);
DISPLAY 0.680851 (-1735 4035);
PAINT MONO (-1735 4035);
FORCEPROP 0 LASTPIN (-1725 4075) $PN 244
J 2
(-1735 4085);
DISPLAY 0.680851 (-1735 4085);
PAINT MONO (-1735 4085);
FORCEPROP 0 LASTPIN (-1725 4125) $PN 246
J 2
(-1735 4135);
DISPLAY 0.680851 (-1735 4135);
PAINT MONO (-1735 4135);
FORCEPROP 0 LASTPIN (-1725 4175) $PN 248
J 2
(-1735 4185);
DISPLAY 0.680851 (-1735 4185);
PAINT MONO (-1735 4185);
FORCEPROP 0 LASTPIN (-1725 4225) $PN 251
J 2
(-1735 4235);
DISPLAY 0.680851 (-1735 4235);
PAINT MONO (-1735 4235);
FORCEPROP 0 LASTPIN (-1725 4275) $PN 253
J 2
(-1735 4285);
DISPLAY 0.680851 (-1735 4285);
PAINT MONO (-1735 4285);
FORCEPROP 0 LASTPIN (-1725 4325) $PN 255
J 2
(-1735 4335);
DISPLAY 0.680851 (-1735 4335);
PAINT MONO (-1735 4335);
FORCEPROP 0 LASTPIN (-1725 4375) $PN 257
J 2
(-1735 4385);
DISPLAY 0.680851 (-1735 4385);
PAINT MONO (-1735 4385);
FORCEPROP 0 LASTPIN (-1725 4425) $PN 259
J 2
(-1735 4435);
DISPLAY 0.680851 (-1735 4435);
PAINT MONO (-1735 4435);
FORCEPROP 0 LASTPIN (-1725 4475) $PN 262
J 2
(-1735 4485);
DISPLAY 0.680851 (-1735 4485);
PAINT MONO (-1735 4485);
FORCEPROP 0 LASTPIN (-1725 4525) $PN 264
J 2
(-1735 4535);
DISPLAY 0.680851 (-1735 4535);
PAINT MONO (-1735 4535);
FORCEPROP 0 LASTPIN (-1725 4575) $PN 266
J 2
(-1735 4585);
DISPLAY 0.680851 (-1735 4585);
PAINT MONO (-1735 4585);
FORCEPROP 0 LASTPIN (-1725 4625) $PN 268
J 2
(-1735 4635);
DISPLAY 0.680851 (-1735 4635);
PAINT MONO (-1735 4635);
FORCEPROP 0 LASTPIN (-1725 4675) $PN 270
J 2
(-1735 4685);
DISPLAY 0.680851 (-1735 4685);
PAINT MONO (-1735 4685);
FORCEPROP 0 LASTPIN (-1725 4725) $PN 273
J 2
(-1735 4735);
DISPLAY 0.680851 (-1735 4735);
PAINT MONO (-1735 4735);
FORCEPROP 0 LASTPIN (-1725 4775) $PN 275
J 2
(-1735 4785);
DISPLAY 0.680851 (-1735 4785);
PAINT MONO (-1735 4785);
FORCEPROP 0 LASTPIN (-1725 4825) $PN 277
J 2
(-1735 4835);
DISPLAY 0.680851 (-1735 4835);
PAINT MONO (-1735 4835);
FORCEPROP 0 LASTPIN (-1725 4875) $PN 279
J 2
(-1735 4885);
DISPLAY 0.680851 (-1735 4885);
PAINT MONO (-1735 4885);
FORCEPROP 0 LASTPIN (-1725 4925) $PN 281
J 2
(-1735 4935);
DISPLAY 0.680851 (-1735 4935);
PAINT MONO (-1735 4935);
FORCEPROP 0 LASTPIN (-1725 4975) $PN 284
J 2
(-1735 4985);
DISPLAY 0.680851 (-1735 4985);
PAINT MONO (-1735 4985);
FORCEPROP 0 LASTPIN (-1725 5025) $PN 286
J 2
(-1735 5035);
DISPLAY 0.680851 (-1735 5035);
PAINT MONO (-1735 5035);
FORCEPROP 0 LASTPIN (-1725 5075) $PN 288
J 2
(-1735 5085);
DISPLAY 0.680851 (-1735 5085);
PAINT MONO (-1735 5085);
FORCEPROP 1 LAST MATERIAL IO
J 0
(-1575 5400);
DISPLAY 0.468085 (-1575 5400);
PAINT SKYBLUE (-1575 5400);
FORCEPROP 2 LAST VALUE SCONN288_DDR506112002KQ
J 0
(-1575 5600);
DISPLAY 0.489362 (-1575 5600);
PAINT SKYBLUE (-1575 5600);
FORCEPROP 2 LAST PART_TYPE SMLF
J 0
(-1575 5650);
DISPLAY 1.021277 (-1575 5650);
FORCEPROP 2 LAST CDS_LIB pure_quanta
J 0
(-1125 3575);
DISPLAY INVISIBLE (-1125 3575);
FORCEPROP 1 LAST NEEDS_NO_SIZE TRUE
J 0
(-1125 3575);
DISPLAY 0.723404 (-1125 3575);
PAINT GREEN (-1125 3575);
DISPLAY INVISIBLE (-1125 3575);
FORCEPROP 1 LAST CDS_LMAN_SYM_OUTLINE -450,1800,450,-1750
J 0
(-1125 3575);
DISPLAY 0.468085 (-1125 3575);
PAINT GREEN (-1125 3575);
DISPLAY INVISIBLE (-1125 3575);
FORCEPROP 1 LAST PATH I143
J 0
(-1125 3575);
DISPLAY 0.723404 (-1125 3575);
PAINT GREEN (-1125 3575);
DISPLAY INVISIBLE (-1125 3575);
FORCEPROP 1 LAST PART_NUMBER DFHST8FS479
J 0
(-1575 5475);
DISPLAY 0.468085 (-1575 5475);
PAINT SKYBLUE (-1575 5475);
DISPLAY INVISIBLE (-1575 5475);
FORCEADD OFFPAGE..1
(-8150 4175);
FORCEPROP 2 LAST $XR0 46 
J 0
(-8401 4175);
DISPLAY 0.638298 (-8401 4175);
PAINT MONO (-8401 4175);
FORCEPROP 2 LAST CDS_LIB mstr_standard
J 0
(-8150 4175);
DISPLAY 0.808511 (-8150 4175);
DISPLAY INVISIBLE (-8150 4175);
FORCEPROP 1 LAST OFFPAGE TRUE
J 0
(-7825 4050);
DISPLAY 0.872340 (-7825 4050);
PAINT GREEN (-7825 4050);
DISPLAY INVISIBLE (-7825 4050);
FORCEPROP 1 LAST COMMENT_BODY TRUE
J 0
(-8025 4075);
DISPLAY 0.872340 (-8025 4075);
PAINT GREEN (-8025 4075);
DISPLAY INVISIBLE (-8025 4075);
FORCEPROP 2 LAST PATH I15
J 0
(-8400 4225);
DISPLAY 1.021277 (-8400 4225);
DISPLAY INVISIBLE (-8400 4225);
FORCEADD OFFPAGE..1
(-8150 4225);
FORCEPROP 2 LAST $XR0 46 
J 0
(-8401 4225);
DISPLAY 0.638298 (-8401 4225);
PAINT MONO (-8401 4225);
FORCEPROP 2 LAST CDS_LIB mstr_standard
J 0
(-8150 4225);
DISPLAY 0.723404 (-8150 4225);
PAINT MONO (-8150 4225);
DISPLAY INVISIBLE (-8150 4225);
FORCEPROP 1 LAST OFFPAGE TRUE
J 0
(-7825 4100);
DISPLAY 0.872340 (-7825 4100);
PAINT GREEN (-7825 4100);
DISPLAY INVISIBLE (-7825 4100);
FORCEPROP 1 LAST COMMENT_BODY TRUE
J 0
(-8025 4125);
DISPLAY 0.872340 (-8025 4125);
PAINT GREEN (-8025 4125);
DISPLAY INVISIBLE (-8025 4125);
FORCEPROP 2 LAST PATH I16
J 0
(-8400 4275);
DISPLAY 1.021277 (-8400 4275);
DISPLAY INVISIBLE (-8400 4275);
FORCEADD OFFPAGE..1
(-8150 4375);
FORCEPROP 2 LAST $XR0 46 
J 0
(-8401 4375);
DISPLAY 0.638298 (-8401 4375);
PAINT MONO (-8401 4375);
FORCEPROP 2 LAST CDS_LIB mstr_standard
J 0
(-8150 4375);
DISPLAY 0.723404 (-8150 4375);
PAINT MONO (-8150 4375);
DISPLAY INVISIBLE (-8150 4375);
FORCEPROP 1 LAST OFFPAGE TRUE
J 0
(-7825 4250);
DISPLAY 0.872340 (-7825 4250);
PAINT GREEN (-7825 4250);
DISPLAY INVISIBLE (-7825 4250);
FORCEPROP 1 LAST COMMENT_BODY TRUE
J 0
(-8025 4275);
DISPLAY 0.872340 (-8025 4275);
PAINT GREEN (-8025 4275);
DISPLAY INVISIBLE (-8025 4275);
FORCEPROP 2 LAST PATH I17
J 0
(-8400 4425);
DISPLAY 1.021277 (-8400 4425);
DISPLAY INVISIBLE (-8400 4425);
FORCEADD OFFPAGE..1
(-8150 4525);
FORCEPROP 2 LAST $XR0 46 
J 0
(-8401 4525);
DISPLAY 0.638298 (-8401 4525);
PAINT MONO (-8401 4525);
FORCEPROP 2 LAST CDS_LIB mstr_standard
J 0
(-8150 4525);
DISPLAY 0.723404 (-8150 4525);
PAINT MONO (-8150 4525);
DISPLAY INVISIBLE (-8150 4525);
FORCEPROP 1 LAST OFFPAGE TRUE
J 0
(-7825 4400);
DISPLAY 0.872340 (-7825 4400);
PAINT GREEN (-7825 4400);
DISPLAY INVISIBLE (-7825 4400);
FORCEPROP 1 LAST COMMENT_BODY TRUE
J 0
(-8025 4425);
DISPLAY 0.872340 (-8025 4425);
PAINT GREEN (-8025 4425);
DISPLAY INVISIBLE (-8025 4425);
FORCEPROP 2 LAST PATH I18
J 0
(-8400 4575);
DISPLAY 1.021277 (-8400 4575);
DISPLAY INVISIBLE (-8400 4575);
FORCEADD Q_CAP..1
R 2
(-8525 3150);
FORCEPROP 1 LAST LOCATION C172
J 2
(-8575 3250);
DISPLAY 0.489362 (-8575 3250);
PAINT SKYBLUE (-8575 3250);
FORCEPROP 0 LAST $SEC 1
J 0
(-8575 3300);
DISPLAY 0.680851 (-8575 3300);
PAINT MONO (-8575 3300);
DISPLAY INVISIBLE (-8575 3300);
FORCEPROP 0 LAST CDS_SEC 1
J 0
(-8575 3300);
DISPLAY 1.021277 (-8575 3300);
DISPLAY INVISIBLE (-8575 3300);
FORCEPROP 1 LASTPIN (-8525 3250) $PN 1
J 2
(-8535 3230);
DISPLAY 0.489362 (-8535 3230);
PAINT MONO (-8535 3230);
FORCEPROP 1 LASTPIN (-8525 3050) $PN 2
J 2
(-8535 3030);
DISPLAY 0.489362 (-8535 3030);
PAINT MONO (-8535 3030);
FORCEPROP 1 LAST MATERIAL X7R
J 2
(-8575 3050);
DISPLAY 0.489362 (-8575 3050);
PAINT SKYBLUE (-8575 3050);
FORCEPROP 1 LAST VALUE 0.1UF
J 2
(-8575 3200);
DISPLAY 0.489362 (-8575 3200);
PAINT SKYBLUE (-8575 3200);
FORCEPROP 1 LAST TOLERANCE 10%
J 2
(-8575 3100);
DISPLAY 0.489362 (-8575 3100);
PAINT SKYBLUE (-8575 3100);
FORCEPROP 1 LAST PACK_TYPE 0402
J 2
(-8575 2950);
DISPLAY 0.489362 (-8575 2950);
PAINT SKYBLUE (-8575 2950);
FORCEPROP 1 LAST VOLTAGE 25V
J 2
(-8575 3150);
DISPLAY 0.489362 (-8575 3150);
PAINT SKYBLUE (-8575 3150);
FORCEPROP 0 LAST BOM_COST MEM
J 2
(-8580 3295);
DISPLAY 0.595745 (-8580 3295);
PAINT MONO (-8580 3295);
DISPLAY INVISIBLE (-8580 3295);
FORCEPROP 2 LAST CDS_LIB pure_quanta
J 0
(-8525 3150);
DISPLAY INVISIBLE (-8525 3150);
FORCEPROP 2 LAST ROOM 
J 2
(-8580 3295);
DISPLAY 0.595745 (-8580 3295);
PAINT RED (-8580 3295);
DISPLAY INVISIBLE (-8580 3295);
FORCEPROP 1 LAST PATH I185
J 2
(-8575 3300);
DISPLAY 0.978723 (-8575 3300);
PAINT WHITE (-8575 3300);
DISPLAY INVISIBLE (-8575 3300);
FORCEPROP 1 LAST PART_NUMBER CH4104K1B00
J 2
(-8575 3000);
DISPLAY 0.489362 (-8575 3000);
PAINT SKYBLUE (-8575 3000);
DISPLAY INVISIBLE (-8575 3000);
FORCEADD GND..1
(-8525 2925);
FORCEPROP 3 LASTPIN (-8525 2975) SIG_NAME GND\g
J 0
(-8515 2985);
DISPLAY 0.659574 (-8515 2985);
PAINT MONO (-8515 2985);
DISPLAY INVISIBLE (-8515 2985);
FORCEPROP 2 LAST ROOM MEM_EFGH_DECOUPLING_CAPS
J 0
(-8500 3000);
DISPLAY 0.659574 (-8500 3000);
PAINT RED (-8500 3000);
DISPLAY INVISIBLE (-8500 3000);
FORCEPROP 1 LAST VOLTAGE 0
J 0
(-8545 3020);
DISPLAY 0.829787 (-8545 3020);
PAINT SKYBLUE (-8545 3020);
DISPLAY INVISIBLE (-8545 3020);
FORCEPROP 2 LAST CDS_LIB mstr_symbols
J 0
(-8525 2925);
DISPLAY 0.808511 (-8525 2925);
DISPLAY INVISIBLE (-8525 2925);
FORCEPROP 1 LAST SIZE 1B
J 0
(-8450 2875);
DISPLAY 0.723404 (-8450 2875);
PAINT GREEN (-8450 2875);
DISPLAY INVISIBLE (-8450 2875);
FORCEPROP 2 LAST BOM_COST MEM
J 0
(-8500 3050);
DISPLAY 0.659574 (-8500 3050);
DISPLAY INVISIBLE (-8500 3050);
FORCEPROP 1 LAST BODY_TYPE PLUMBING
J 0
(-8570 2882);
DISPLAY 0.276596 (-8570 2882);
PAINT GREEN (-8570 2882);
DISPLAY INVISIBLE (-8570 2882);
FORCEPROP 1 LAST HDL_POWER GND
J 0
(-8525 3075);
DISPLAY 0.723404 (-8525 3075);
PAINT GREEN (-8525 3075);
DISPLAY INVISIBLE (-8525 3075);
FORCEPROP 1 LAST PATH I186
J 0
(-8450 2925);
DISPLAY 0.872340 (-8450 2925);
PAINT AQUA (-8450 2925);
DISPLAY INVISIBLE (-8450 2925);
FORCEADD OFFPAGE..6
(-8925 2075);
FORCEPROP 2 LAST $XR4 109 
J 0
(-9205 2111);
DISPLAY 0.638298 (-9205 2111);
PAINT MONO (-9205 2111);
FORCEPROP 2 LAST $XR3 108 
J 0
(-9325 2039);
DISPLAY 0.638298 (-9325 2039);
PAINT MONO (-9325 2039);
FORCEPROP 2 LAST $XR2 106 
J 0
(-9205 2039);
DISPLAY 0.638298 (-9205 2039);
PAINT MONO (-9205 2039);
FORCEPROP 2 LAST $XR1 105 
J 0
(-9325 2075);
DISPLAY 0.638298 (-9325 2075);
PAINT MONO (-9325 2075);
FORCEPROP 2 LAST $XR0 104 
J 0
(-9205 2075);
DISPLAY 0.638298 (-9205 2075);
PAINT MONO (-9205 2075);
FORCEPROP 2 LAST CDS_LIB mstr_standard
J 0
(-8925 2075);
DISPLAY INVISIBLE (-8925 2075);
FORCEPROP 1 LAST OFFPAGE TRUE
J 0
(-8600 1950);
DISPLAY 0.872340 (-8600 1950);
PAINT GREEN (-8600 1950);
DISPLAY INVISIBLE (-8600 1950);
FORCEPROP 1 LAST COMMENT_BODY TRUE
J 0
(-8825 2000);
DISPLAY 0.872340 (-8825 2000);
PAINT GREEN (-8825 2000);
DISPLAY INVISIBLE (-8825 2000);
FORCEPROP 2 LAST PATH I187
J 0
(-8875 2150);
DISPLAY 1.021277 (-8875 2150);
DISPLAY INVISIBLE (-8875 2150);
FORCEADD Q_RES..1
R 2
(-8375 2075);
FORCEPROP 1 LAST LOCATION R312
J 2
(-8325 2125);
DISPLAY 0.489362 (-8325 2125);
PAINT SKYBLUE (-8325 2125);
FORCEPROP 0 LAST $SEC 1
J 0
(-8325 2175);
DISPLAY 0.680851 (-8325 2175);
PAINT MONO (-8325 2175);
DISPLAY INVISIBLE (-8325 2175);
FORCEPROP 0 LAST CDS_SEC 1
J 0
(-8325 2175);
DISPLAY 1.021277 (-8325 2175);
DISPLAY INVISIBLE (-8325 2175);
FORCEPROP 1 LASTPIN (-8275 2075) $PN 1
J 2
(-8287 2087);
DISPLAY 0.489362 (-8287 2087);
PAINT MONO (-8287 2087);
FORCEPROP 1 LASTPIN (-8475 2075) $PN 2
J 2
(-8437 2087);
DISPLAY 0.489362 (-8437 2087);
PAINT MONO (-8437 2087);
FORCEPROP 1 LAST VALUE 1K
J 0
(-8375 2025);
DISPLAY 0.489362 (-8375 2025);
PAINT SKYBLUE (-8375 2025);
FORCEPROP 1 LAST PACK_TYPE 0402LF
J 0
(-8550 2000);
DISPLAY 0.489362 (-8550 2000);
PAINT SKYBLUE (-8550 2000);
DISPLAY INVISIBLE (-8550 2000);
FORCEPROP 1 LAST MATERIAL CHIP
J 0
(-8550 2050);
DISPLAY 0.489362 (-8550 2050);
PAINT SKYBLUE (-8550 2050);
DISPLAY INVISIBLE (-8550 2050);
FORCEPROP 1 LAST WATTAGE 1/16W
J 0
(-8300 2000);
DISPLAY 0.489362 (-8300 2000);
PAINT SKYBLUE (-8300 2000);
DISPLAY INVISIBLE (-8300 2000);
FORCEPROP 2 LAST CDS_LIB pure_quanta
J 0
(-8375 2075);
DISPLAY INVISIBLE (-8375 2075);
FORCEPROP 2 LAST BOM_COST MEM
J 0
(-8400 2225);
DISPLAY 0.744681 (-8400 2225);
PAINT WHITE (-8400 2225);
DISPLAY INVISIBLE (-8400 2225);
FORCEPROP 1 LAST TOLERANCE 1%
J 2
(-8250 2050);
DISPLAY 0.489362 (-8250 2050);
PAINT SKYBLUE (-8250 2050);
DISPLAY INVISIBLE (-8250 2050);
FORCEPROP 2 LAST ROOM 
J 0
(-8400 2175);
DISPLAY 0.744681 (-8400 2175);
PAINT RED (-8400 2175);
DISPLAY INVISIBLE (-8400 2175);
FORCEPROP 1 LAST PATH I188
J 2
(-8325 2225);
DISPLAY 0.978723 (-8325 2225);
PAINT WHITE (-8325 2225);
DISPLAY INVISIBLE (-8325 2225);
FORCEPROP 1 LAST PART_NUMBER CS21002FB06
J 0
(-8475 2125);
DISPLAY 0.489362 (-8475 2125);
PAINT SKYBLUE (-8475 2125);
DISPLAY INVISIBLE (-8475 2125);
FORCEADD VCC_CORE..1
(-8250 2400);
FORCEPROP 3 LASTPIN (-8250 2350) SIG_NAME P3V3\g
J 0
(-8240 2360);
DISPLAY 0.659574 (-8240 2360);
PAINT MONO (-8240 2360);
DISPLAY INVISIBLE (-8240 2360);
FORCEPROP 1 LAST HDL_POWER P3V3
J 1
(-8250 2450);
DISPLAY 0.489362 (-8250 2450);
PAINT GREEN (-8250 2450);
FORCEPROP 2 LAST ROOM PVCCINFAON_CPU0_CTRL
J 0
(-8250 2500);
DISPLAY 0.808511 (-8250 2500);
PAINT RED (-8250 2500);
DISPLAY INVISIBLE (-8250 2500);
FORCEPROP 0 LAST VOLTAGE 3.3
J 0
(-8525 2550);
DISPLAY 1.021277 (-8525 2550);
PAINT SKYBLUE (-8525 2550);
DISPLAY INVISIBLE (-8525 2550);
FORCEPROP 2 LAST CDS_LIB mstr_symbols
J 0
(-8250 2400);
DISPLAY INVISIBLE (-8250 2400);
FORCEPROP 1 LAST PATH I189
J 0
(-8200 2425);
DISPLAY 0.872340 (-8200 2425);
PAINT AQUA (-8200 2425);
DISPLAY INVISIBLE (-8200 2425);
FORCEADD OFFPAGE..1
(-8150 4475);
FORCEPROP 2 LAST $XR0 46 
J 0
(-8401 4475);
DISPLAY 0.638298 (-8401 4475);
PAINT MONO (-8401 4475);
FORCEPROP 2 LAST CDS_LIB mstr_standard
J 0
(-8150 4475);
DISPLAY 0.808511 (-8150 4475);
DISPLAY INVISIBLE (-8150 4475);
FORCEPROP 1 LAST OFFPAGE TRUE
J 0
(-7825 4350);
DISPLAY 0.872340 (-7825 4350);
PAINT GREEN (-7825 4350);
DISPLAY INVISIBLE (-7825 4350);
FORCEPROP 1 LAST COMMENT_BODY TRUE
J 0
(-8025 4375);
DISPLAY 0.872340 (-8025 4375);
PAINT GREEN (-8025 4375);
DISPLAY INVISIBLE (-8025 4375);
FORCEPROP 2 LAST PATH I19
J 0
(-8400 4525);
DISPLAY 1.021277 (-8400 4525);
DISPLAY INVISIBLE (-8400 4525);
FORCEADD Q_RES..2
(-8250 2225);
FORCEPROP 1 LAST LOCATION R113
J 0
(-8205 2350);
DISPLAY 0.489362 (-8205 2350);
PAINT SKYBLUE (-8205 2350);
FORCEPROP 0 LAST $SEC 1
J 0
(-8200 2400);
DISPLAY 0.680851 (-8200 2400);
PAINT MONO (-8200 2400);
DISPLAY INVISIBLE (-8200 2400);
FORCEPROP 0 LAST CDS_SEC 1
J 0
(-8200 2400);
DISPLAY 1.021277 (-8200 2400);
DISPLAY INVISIBLE (-8200 2400);
FORCEPROP 1 LASTPIN (-8250 2325) $PN 1
J 0
(-8245 2287);
DISPLAY 0.489362 (-8245 2287);
PAINT MONO (-8245 2287);
FORCEPROP 1 LASTPIN (-8250 2125) $PN 2
J 0
(-8245 2135);
DISPLAY 0.489362 (-8245 2135);
PAINT MONO (-8245 2135);
FORCEPROP 1 LAST WATTAGE 1/16W
J 0
(-8200 2250);
DISPLAY 0.489362 (-8200 2250);
PAINT SKYBLUE (-8200 2250);
FORCEPROP 1 LAST PACK_TYPE 0402LF
J 0
(-8200 2175);
DISPLAY 0.489362 (-8200 2175);
PAINT SKYBLUE (-8200 2175);
FORCEPROP 1 LAST MATERIAL EMPTY
J 0
(-8200 2225);
DISPLAY 0.489362 (-8200 2225);
PAINT RED (-8200 2225);
FORCEPROP 1 LAST VALUE 1K
J 0
(-8205 2300);
DISPLAY 0.489362 (-8205 2300);
PAINT SKYBLUE (-8205 2300);
FORCEPROP 1 LAST TOLERANCE 1%
J 0
(-8200 2275);
DISPLAY 0.489362 (-8200 2275);
PAINT SKYBLUE (-8200 2275);
FORCEPROP 2 LAST CDS_LIB pure_quanta
J 0
(-8250 2225);
DISPLAY INVISIBLE (-8250 2225);
FORCEPROP 2 LAST BOM_COST MEM
J 0
(-8200 2400);
DISPLAY 0.808511 (-8200 2400);
DISPLAY INVISIBLE (-8200 2400);
FORCEPROP 2 LAST ROOM 
J 0
(-8200 2450);
DISPLAY 0.808511 (-8200 2450);
PAINT RED (-8200 2450);
DISPLAY INVISIBLE (-8200 2450);
FORCEPROP 1 LAST PATH I190
J 0
(-8200 2400);
DISPLAY 0.978723 (-8200 2400);
PAINT WHITE (-8200 2400);
DISPLAY INVISIBLE (-8200 2400);
FORCEPROP 1 LAST PART_NUMBER CS21002FB06
J 0
(-8200 2200);
DISPLAY 0.489362 (-8200 2200);
PAINT SKYBLUE (-8200 2200);
DISPLAY INVISIBLE (-8200 2200);
FORCEADD OFFPAGE..2
(-2350 4700);
FORCEPROP 2 LAST $XR0 46 
J 0
(-2161 4700);
DISPLAY 0.638298 (-2161 4700);
PAINT MONO (-2161 4700);
FORCEPROP 2 LAST CDS_LIB mstr_standard
J 0
(-2350 4700);
DISPLAY 0.723404 (-2350 4700);
PAINT MONO (-2350 4700);
DISPLAY INVISIBLE (-2350 4700);
FORCEPROP 1 LAST OFFPAGE TRUE
J 0
(-2025 4575);
DISPLAY 0.723404 (-2025 4575);
PAINT GREEN (-2025 4575);
DISPLAY INVISIBLE (-2025 4575);
FORCEPROP 1 LAST COMMENT_BODY TRUE
J 0
(-2395 4605);
DISPLAY 0.872340 (-2395 4605);
PAINT GREEN (-2395 4605);
DISPLAY INVISIBLE (-2395 4605);
FORCEPROP 2 LAST PATH I192
J 0
(-2150 4750);
DISPLAY 0.680851 (-2150 4750);
DISPLAY INVISIBLE (-2150 4750);
FORCEADD OFFPAGE..2
(-2350 4650);
FORCEPROP 2 LAST $XR0 46 
J 0
(-2161 4650);
DISPLAY 0.638298 (-2161 4650);
PAINT MONO (-2161 4650);
FORCEPROP 2 LAST CDS_LIB mstr_standard
J 0
(-2350 4650);
DISPLAY 0.723404 (-2350 4650);
PAINT MONO (-2350 4650);
DISPLAY INVISIBLE (-2350 4650);
FORCEPROP 1 LAST OFFPAGE TRUE
J 0
(-2025 4525);
DISPLAY 0.723404 (-2025 4525);
PAINT GREEN (-2025 4525);
DISPLAY INVISIBLE (-2025 4525);
FORCEPROP 1 LAST COMMENT_BODY TRUE
J 0
(-2395 4555);
DISPLAY 0.872340 (-2395 4555);
PAINT GREEN (-2395 4555);
DISPLAY INVISIBLE (-2395 4555);
FORCEPROP 2 LAST PATH I193
J 0
(-2150 4700);
DISPLAY 0.680851 (-2150 4700);
DISPLAY INVISIBLE (-2150 4700);
FORCEADD OFFPAGE..2
(-2350 3650);
FORCEPROP 2 LAST $XR0 46 
J 0
(-2161 3650);
DISPLAY 0.638298 (-2161 3650);
PAINT MONO (-2161 3650);
FORCEPROP 2 LAST CDS_LIB mstr_standard
J 0
(-2350 3650);
DISPLAY 0.723404 (-2350 3650);
PAINT MONO (-2350 3650);
DISPLAY INVISIBLE (-2350 3650);
FORCEPROP 1 LAST OFFPAGE TRUE
J 0
(-2025 3525);
DISPLAY 0.723404 (-2025 3525);
PAINT GREEN (-2025 3525);
DISPLAY INVISIBLE (-2025 3525);
FORCEPROP 1 LAST COMMENT_BODY TRUE
J 0
(-2395 3555);
DISPLAY 0.872340 (-2395 3555);
PAINT GREEN (-2395 3555);
DISPLAY INVISIBLE (-2395 3555);
FORCEPROP 2 LAST PATH I194
J 0
(-2150 3700);
DISPLAY 0.680851 (-2150 3700);
DISPLAY INVISIBLE (-2150 3700);
FORCEADD OFFPAGE..2
(-2350 3600);
FORCEPROP 2 LAST $XR0 46 
J 0
(-2161 3600);
DISPLAY 0.638298 (-2161 3600);
PAINT MONO (-2161 3600);
FORCEPROP 2 LAST CDS_LIB mstr_standard
J 0
(-2350 3600);
DISPLAY 0.723404 (-2350 3600);
PAINT MONO (-2350 3600);
DISPLAY INVISIBLE (-2350 3600);
FORCEPROP 1 LAST OFFPAGE TRUE
J 0
(-2025 3475);
DISPLAY 0.723404 (-2025 3475);
PAINT GREEN (-2025 3475);
DISPLAY INVISIBLE (-2025 3475);
FORCEPROP 1 LAST COMMENT_BODY TRUE
J 0
(-2395 3505);
DISPLAY 0.872340 (-2395 3505);
PAINT GREEN (-2395 3505);
DISPLAY INVISIBLE (-2395 3505);
FORCEPROP 2 LAST PATH I195
J 0
(-2150 3650);
DISPLAY 0.680851 (-2150 3650);
DISPLAY INVISIBLE (-2150 3650);
FORCEADD TAP..1
(-3150 4600);
FORCEPROP 3 LASTPIN (-3200 4600) SIG_NAME M_J_CPU1_SA_DQS_DN<9>
J 0
(-3190 4610);
DISPLAY 0.659574 (-3190 4610);
PAINT MONO (-3190 4610);
DISPLAY INVISIBLE (-3190 4610);
FORCEPROP 1 LASTPIN (-3200 4600) BN 9
J 0
(-3212 4608);
DISPLAY 0.489362 (-3212 4608);
PAINT GREEN (-3212 4608);
FORCEPROP 2 LAST CDS_LIB mstr_standard
J 0
(-3150 4600);
DISPLAY 0.723404 (-3150 4600);
PAINT MONO (-3150 4600);
DISPLAY INVISIBLE (-3150 4600);
FORCEPROP 1 LAST BODY_TYPE PLUMBING
J 0
(-3150 4650);
DISPLAY 0.872340 (-3150 4650);
PAINT GREEN (-3150 4650);
DISPLAY INVISIBLE (-3150 4650);
FORCEPROP 1 LAST HDL_TAP TRUE
J 0
(-2825 4475);
DISPLAY 0.872340 (-2825 4475);
DISPLAY INVISIBLE (-2825 4475);
FORCEPROP 1 LAST PATH I196
J 0
(-3152 4600);
DISPLAY 0.872340 (-3152 4600);
PAINT GREEN (-3152 4600);
DISPLAY INVISIBLE (-3152 4600);
FORCEADD TAP..1
(-3350 4650);
FORCEPROP 3 LASTPIN (-3400 4650) SIG_NAME M_J_CPU1_SA_DQS_DP<9>
J 0
(-3390 4660);
DISPLAY 0.659574 (-3390 4660);
PAINT MONO (-3390 4660);
DISPLAY INVISIBLE (-3390 4660);
FORCEPROP 1 LASTPIN (-3400 4650) BN 9
J 0
(-3412 4658);
DISPLAY 0.489362 (-3412 4658);
PAINT GREEN (-3412 4658);
FORCEPROP 2 LAST CDS_LIB mstr_standard
J 0
(-3350 4650);
DISPLAY 0.723404 (-3350 4650);
PAINT MONO (-3350 4650);
DISPLAY INVISIBLE (-3350 4650);
FORCEPROP 1 LAST BODY_TYPE PLUMBING
J 0
(-3350 4700);
DISPLAY 0.872340 (-3350 4700);
PAINT GREEN (-3350 4700);
DISPLAY INVISIBLE (-3350 4700);
FORCEPROP 1 LAST HDL_TAP TRUE
J 0
(-3025 4525);
DISPLAY 0.872340 (-3025 4525);
DISPLAY INVISIBLE (-3025 4525);
FORCEPROP 1 LAST PATH I197
J 0
(-3352 4650);
DISPLAY 0.872340 (-3352 4650);
PAINT GREEN (-3352 4650);
DISPLAY INVISIBLE (-3352 4650);
FORCEADD TAP..1
(-3350 4550);
FORCEPROP 3 LASTPIN (-3400 4550) SIG_NAME M_J_CPU1_SA_DQS_DP<8>
J 0
(-3390 4560);
DISPLAY 0.659574 (-3390 4560);
PAINT MONO (-3390 4560);
DISPLAY INVISIBLE (-3390 4560);
FORCEPROP 1 LASTPIN (-3400 4550) BN 8
J 0
(-3412 4558);
DISPLAY 0.489362 (-3412 4558);
PAINT GREEN (-3412 4558);
FORCEPROP 2 LAST CDS_LIB mstr_standard
J 0
(-3350 4550);
DISPLAY 0.723404 (-3350 4550);
PAINT MONO (-3350 4550);
DISPLAY INVISIBLE (-3350 4550);
FORCEPROP 1 LAST BODY_TYPE PLUMBING
J 0
(-3350 4600);
DISPLAY 0.872340 (-3350 4600);
PAINT GREEN (-3350 4600);
DISPLAY INVISIBLE (-3350 4600);
FORCEPROP 1 LAST HDL_TAP TRUE
J 0
(-3025 4425);
DISPLAY 0.872340 (-3025 4425);
DISPLAY INVISIBLE (-3025 4425);
FORCEPROP 1 LAST PATH I198
J 0
(-3352 4550);
DISPLAY 0.872340 (-3352 4550);
PAINT GREEN (-3352 4550);
DISPLAY INVISIBLE (-3352 4550);
FORCEADD TAP..1
(-3150 4500);
FORCEPROP 3 LASTPIN (-3200 4500) SIG_NAME M_J_CPU1_SA_DQS_DN<8>
J 0
(-3190 4510);
DISPLAY 0.659574 (-3190 4510);
PAINT MONO (-3190 4510);
DISPLAY INVISIBLE (-3190 4510);
FORCEPROP 1 LASTPIN (-3200 4500) BN 8
J 0
(-3212 4508);
DISPLAY 0.489362 (-3212 4508);
PAINT GREEN (-3212 4508);
FORCEPROP 2 LAST CDS_LIB mstr_standard
J 0
(-3150 4500);
DISPLAY 0.723404 (-3150 4500);
PAINT MONO (-3150 4500);
DISPLAY INVISIBLE (-3150 4500);
FORCEPROP 1 LAST BODY_TYPE PLUMBING
J 0
(-3150 4550);
DISPLAY 0.872340 (-3150 4550);
PAINT GREEN (-3150 4550);
DISPLAY INVISIBLE (-3150 4550);
FORCEPROP 1 LAST HDL_TAP TRUE
J 0
(-2825 4375);
DISPLAY 0.872340 (-2825 4375);
DISPLAY INVISIBLE (-2825 4375);
FORCEPROP 1 LAST PATH I199
J 0
(-3152 4500);
DISPLAY 0.872340 (-3152 4500);
PAINT GREEN (-3152 4500);
DISPLAY INVISIBLE (-3152 4500);
FORCEADD OFFPAGE..1
(-8150 4975);
FORCEPROP 2 LAST $XR0 46 
J 0
(-8401 4975);
DISPLAY 0.638298 (-8401 4975);
PAINT MONO (-8401 4975);
FORCEPROP 2 LAST CDS_LIB mstr_standard
J 0
(-8150 4975);
DISPLAY 0.723404 (-8150 4975);
PAINT MONO (-8150 4975);
DISPLAY INVISIBLE (-8150 4975);
FORCEPROP 1 LAST OFFPAGE TRUE
J 0
(-7825 4850);
DISPLAY 0.872340 (-7825 4850);
PAINT GREEN (-7825 4850);
DISPLAY INVISIBLE (-7825 4850);
FORCEPROP 1 LAST COMMENT_BODY TRUE
J 0
(-8025 4875);
DISPLAY 0.872340 (-8025 4875);
PAINT GREEN (-8025 4875);
DISPLAY INVISIBLE (-8025 4875);
FORCEPROP 2 LAST PATH I20
J 0
(-8400 5025);
DISPLAY 1.021277 (-8400 5025);
DISPLAY INVISIBLE (-8400 5025);
FORCEADD TAP..1
(-3150 4300);
FORCEPROP 3 LASTPIN (-3200 4300) SIG_NAME M_J_CPU1_SA_DQS_DN<6>
J 0
(-3190 4310);
DISPLAY 0.659574 (-3190 4310);
PAINT MONO (-3190 4310);
DISPLAY INVISIBLE (-3190 4310);
FORCEPROP 1 LASTPIN (-3200 4300) BN 6
J 0
(-3212 4308);
DISPLAY 0.489362 (-3212 4308);
PAINT GREEN (-3212 4308);
FORCEPROP 2 LAST CDS_LIB mstr_standard
J 0
(-3150 4300);
DISPLAY 0.723404 (-3150 4300);
PAINT MONO (-3150 4300);
DISPLAY INVISIBLE (-3150 4300);
FORCEPROP 1 LAST BODY_TYPE PLUMBING
J 0
(-3150 4350);
DISPLAY 0.872340 (-3150 4350);
PAINT GREEN (-3150 4350);
DISPLAY INVISIBLE (-3150 4350);
FORCEPROP 1 LAST HDL_TAP TRUE
J 0
(-2825 4175);
DISPLAY 0.872340 (-2825 4175);
DISPLAY INVISIBLE (-2825 4175);
FORCEPROP 1 LAST PATH I200
J 0
(-3152 4300);
DISPLAY 0.872340 (-3152 4300);
PAINT GREEN (-3152 4300);
DISPLAY INVISIBLE (-3152 4300);
FORCEADD TAP..1
(-3150 4400);
FORCEPROP 3 LASTPIN (-3200 4400) SIG_NAME M_J_CPU1_SA_DQS_DN<7>
J 0
(-3190 4410);
DISPLAY 0.659574 (-3190 4410);
PAINT MONO (-3190 4410);
DISPLAY INVISIBLE (-3190 4410);
FORCEPROP 1 LASTPIN (-3200 4400) BN 7
J 0
(-3212 4408);
DISPLAY 0.489362 (-3212 4408);
PAINT GREEN (-3212 4408);
FORCEPROP 2 LAST CDS_LIB mstr_standard
J 0
(-3150 4400);
DISPLAY 0.723404 (-3150 4400);
PAINT MONO (-3150 4400);
DISPLAY INVISIBLE (-3150 4400);
FORCEPROP 1 LAST BODY_TYPE PLUMBING
J 0
(-3150 4450);
DISPLAY 0.872340 (-3150 4450);
PAINT GREEN (-3150 4450);
DISPLAY INVISIBLE (-3150 4450);
FORCEPROP 1 LAST HDL_TAP TRUE
J 0
(-2825 4275);
DISPLAY 0.872340 (-2825 4275);
DISPLAY INVISIBLE (-2825 4275);
FORCEPROP 1 LAST PATH I201
J 0
(-3152 4400);
DISPLAY 0.872340 (-3152 4400);
PAINT GREEN (-3152 4400);
DISPLAY INVISIBLE (-3152 4400);
FORCEADD TAP..1
(-3150 4200);
FORCEPROP 3 LASTPIN (-3200 4200) SIG_NAME M_J_CPU1_SA_DQS_DN<5>
J 0
(-3190 4210);
DISPLAY 0.659574 (-3190 4210);
PAINT MONO (-3190 4210);
DISPLAY INVISIBLE (-3190 4210);
FORCEPROP 1 LASTPIN (-3200 4200) BN 5
J 0
(-3212 4208);
DISPLAY 0.489362 (-3212 4208);
PAINT GREEN (-3212 4208);
FORCEPROP 2 LAST CDS_LIB mstr_standard
J 0
(-3150 4200);
DISPLAY 0.723404 (-3150 4200);
PAINT MONO (-3150 4200);
DISPLAY INVISIBLE (-3150 4200);
FORCEPROP 1 LAST BODY_TYPE PLUMBING
J 0
(-3150 4250);
DISPLAY 0.872340 (-3150 4250);
PAINT GREEN (-3150 4250);
DISPLAY INVISIBLE (-3150 4250);
FORCEPROP 1 LAST HDL_TAP TRUE
J 0
(-2825 4075);
DISPLAY 0.872340 (-2825 4075);
DISPLAY INVISIBLE (-2825 4075);
FORCEPROP 1 LAST PATH I202
J 0
(-3152 4200);
DISPLAY 0.872340 (-3152 4200);
PAINT GREEN (-3152 4200);
DISPLAY INVISIBLE (-3152 4200);
FORCEADD TAP..1
(-3150 4100);
FORCEPROP 3 LASTPIN (-3200 4100) SIG_NAME M_J_CPU1_SA_DQS_DN<4>
J 0
(-3190 4110);
DISPLAY 0.659574 (-3190 4110);
PAINT MONO (-3190 4110);
DISPLAY INVISIBLE (-3190 4110);
FORCEPROP 1 LASTPIN (-3200 4100) BN 4
J 0
(-3212 4108);
DISPLAY 0.489362 (-3212 4108);
PAINT GREEN (-3212 4108);
FORCEPROP 2 LAST CDS_LIB mstr_standard
J 0
(-3150 4100);
DISPLAY 0.723404 (-3150 4100);
PAINT MONO (-3150 4100);
DISPLAY INVISIBLE (-3150 4100);
FORCEPROP 1 LAST BODY_TYPE PLUMBING
J 0
(-3150 4150);
DISPLAY 0.872340 (-3150 4150);
PAINT GREEN (-3150 4150);
DISPLAY INVISIBLE (-3150 4150);
FORCEPROP 1 LAST HDL_TAP TRUE
J 0
(-2825 3975);
DISPLAY 0.872340 (-2825 3975);
DISPLAY INVISIBLE (-2825 3975);
FORCEPROP 1 LAST PATH I203
J 0
(-3152 4100);
DISPLAY 0.872340 (-3152 4100);
PAINT GREEN (-3152 4100);
DISPLAY INVISIBLE (-3152 4100);
FORCEADD TAP..1
(-3150 4000);
FORCEPROP 3 LASTPIN (-3200 4000) SIG_NAME M_J_CPU1_SA_DQS_DN<3>
J 0
(-3190 4010);
DISPLAY 0.659574 (-3190 4010);
PAINT MONO (-3190 4010);
DISPLAY INVISIBLE (-3190 4010);
FORCEPROP 1 LASTPIN (-3200 4000) BN 3
J 0
(-3212 4008);
DISPLAY 0.489362 (-3212 4008);
PAINT GREEN (-3212 4008);
FORCEPROP 2 LAST CDS_LIB mstr_standard
J 0
(-3150 4000);
DISPLAY 0.723404 (-3150 4000);
PAINT MONO (-3150 4000);
DISPLAY INVISIBLE (-3150 4000);
FORCEPROP 1 LAST BODY_TYPE PLUMBING
J 0
(-3150 4050);
DISPLAY 0.872340 (-3150 4050);
PAINT GREEN (-3150 4050);
DISPLAY INVISIBLE (-3150 4050);
FORCEPROP 1 LAST HDL_TAP TRUE
J 0
(-2825 3875);
DISPLAY 0.872340 (-2825 3875);
DISPLAY INVISIBLE (-2825 3875);
FORCEPROP 1 LAST PATH I204
J 0
(-3152 4000);
DISPLAY 0.872340 (-3152 4000);
PAINT GREEN (-3152 4000);
DISPLAY INVISIBLE (-3152 4000);
FORCEADD TAP..1
(-3150 3800);
FORCEPROP 3 LASTPIN (-3200 3800) SIG_NAME M_J_CPU1_SA_DQS_DN<1>
J 0
(-3190 3810);
DISPLAY 0.659574 (-3190 3810);
PAINT MONO (-3190 3810);
DISPLAY INVISIBLE (-3190 3810);
FORCEPROP 1 LASTPIN (-3200 3800) BN 1
J 0
(-3212 3808);
DISPLAY 0.489362 (-3212 3808);
PAINT GREEN (-3212 3808);
FORCEPROP 2 LAST CDS_LIB mstr_standard
J 0
(-3150 3800);
DISPLAY 0.723404 (-3150 3800);
PAINT MONO (-3150 3800);
DISPLAY INVISIBLE (-3150 3800);
FORCEPROP 1 LAST BODY_TYPE PLUMBING
J 0
(-3150 3850);
DISPLAY 0.872340 (-3150 3850);
PAINT GREEN (-3150 3850);
DISPLAY INVISIBLE (-3150 3850);
FORCEPROP 1 LAST HDL_TAP TRUE
J 0
(-2825 3675);
DISPLAY 0.872340 (-2825 3675);
DISPLAY INVISIBLE (-2825 3675);
FORCEPROP 1 LAST PATH I205
J 0
(-3152 3800);
DISPLAY 0.872340 (-3152 3800);
PAINT GREEN (-3152 3800);
DISPLAY INVISIBLE (-3152 3800);
FORCEADD TAP..1
(-3150 3900);
FORCEPROP 3 LASTPIN (-3200 3900) SIG_NAME M_J_CPU1_SA_DQS_DN<2>
J 0
(-3190 3910);
DISPLAY 0.659574 (-3190 3910);
PAINT MONO (-3190 3910);
DISPLAY INVISIBLE (-3190 3910);
FORCEPROP 1 LASTPIN (-3200 3900) BN 2
J 0
(-3212 3908);
DISPLAY 0.489362 (-3212 3908);
PAINT GREEN (-3212 3908);
FORCEPROP 2 LAST CDS_LIB mstr_standard
J 0
(-3150 3900);
DISPLAY 0.723404 (-3150 3900);
PAINT MONO (-3150 3900);
DISPLAY INVISIBLE (-3150 3900);
FORCEPROP 1 LAST BODY_TYPE PLUMBING
J 0
(-3150 3950);
DISPLAY 0.872340 (-3150 3950);
PAINT GREEN (-3150 3950);
DISPLAY INVISIBLE (-3150 3950);
FORCEPROP 1 LAST HDL_TAP TRUE
J 0
(-2825 3775);
DISPLAY 0.872340 (-2825 3775);
DISPLAY INVISIBLE (-2825 3775);
FORCEPROP 1 LAST PATH I206
J 0
(-3152 3900);
DISPLAY 0.872340 (-3152 3900);
PAINT GREEN (-3152 3900);
DISPLAY INVISIBLE (-3152 3900);
FORCEADD TAP..1
(-3150 3700);
FORCEPROP 3 LASTPIN (-3200 3700) SIG_NAME M_J_CPU1_SA_DQS_DN<0>
J 0
(-3190 3710);
DISPLAY 0.659574 (-3190 3710);
PAINT MONO (-3190 3710);
DISPLAY INVISIBLE (-3190 3710);
FORCEPROP 1 LASTPIN (-3200 3700) BN 0
J 0
(-3212 3708);
DISPLAY 0.489362 (-3212 3708);
PAINT GREEN (-3212 3708);
FORCEPROP 2 LAST CDS_LIB mstr_standard
J 0
(-3150 3700);
DISPLAY 0.723404 (-3150 3700);
PAINT MONO (-3150 3700);
DISPLAY INVISIBLE (-3150 3700);
FORCEPROP 1 LAST BODY_TYPE PLUMBING
J 0
(-3150 3750);
DISPLAY 0.872340 (-3150 3750);
PAINT GREEN (-3150 3750);
DISPLAY INVISIBLE (-3150 3750);
FORCEPROP 1 LAST HDL_TAP TRUE
J 0
(-2825 3575);
DISPLAY 0.872340 (-2825 3575);
DISPLAY INVISIBLE (-2825 3575);
FORCEPROP 1 LAST PATH I207
J 0
(-3152 3700);
DISPLAY 0.872340 (-3152 3700);
PAINT GREEN (-3152 3700);
DISPLAY INVISIBLE (-3152 3700);
FORCEADD TAP..1
(-3150 3550);
FORCEPROP 3 LASTPIN (-3200 3550) SIG_NAME M_J_CPU1_SB_DQS_DN<9>
J 0
(-3190 3560);
DISPLAY 0.659574 (-3190 3560);
PAINT MONO (-3190 3560);
DISPLAY INVISIBLE (-3190 3560);
FORCEPROP 1 LASTPIN (-3200 3550) BN 9
J 0
(-3212 3558);
DISPLAY 0.489362 (-3212 3558);
PAINT GREEN (-3212 3558);
FORCEPROP 2 LAST CDS_LIB mstr_standard
J 0
(-3150 3550);
DISPLAY 0.723404 (-3150 3550);
PAINT MONO (-3150 3550);
DISPLAY INVISIBLE (-3150 3550);
FORCEPROP 1 LAST BODY_TYPE PLUMBING
J 0
(-3150 3600);
DISPLAY 0.872340 (-3150 3600);
PAINT GREEN (-3150 3600);
DISPLAY INVISIBLE (-3150 3600);
FORCEPROP 1 LAST HDL_TAP TRUE
J 0
(-2825 3425);
DISPLAY 0.872340 (-2825 3425);
DISPLAY INVISIBLE (-2825 3425);
FORCEPROP 1 LAST PATH I208
J 0
(-3152 3550);
DISPLAY 0.872340 (-3152 3550);
PAINT GREEN (-3152 3550);
DISPLAY INVISIBLE (-3152 3550);
FORCEADD TAP..1
(-3350 4450);
FORCEPROP 3 LASTPIN (-3400 4450) SIG_NAME M_J_CPU1_SA_DQS_DP<7>
J 0
(-3390 4460);
DISPLAY 0.659574 (-3390 4460);
PAINT MONO (-3390 4460);
DISPLAY INVISIBLE (-3390 4460);
FORCEPROP 1 LASTPIN (-3400 4450) BN 7
J 0
(-3412 4458);
DISPLAY 0.489362 (-3412 4458);
PAINT GREEN (-3412 4458);
FORCEPROP 2 LAST CDS_LIB mstr_standard
J 0
(-3350 4450);
DISPLAY 0.723404 (-3350 4450);
PAINT MONO (-3350 4450);
DISPLAY INVISIBLE (-3350 4450);
FORCEPROP 1 LAST BODY_TYPE PLUMBING
J 0
(-3350 4500);
DISPLAY 0.872340 (-3350 4500);
PAINT GREEN (-3350 4500);
DISPLAY INVISIBLE (-3350 4500);
FORCEPROP 1 LAST HDL_TAP TRUE
J 0
(-3025 4325);
DISPLAY 0.872340 (-3025 4325);
DISPLAY INVISIBLE (-3025 4325);
FORCEPROP 1 LAST PATH I209
J 0
(-3352 4450);
DISPLAY 0.872340 (-3352 4450);
PAINT GREEN (-3352 4450);
DISPLAY INVISIBLE (-3352 4450);
FORCEADD OFFPAGE..1
(-8150 5375);
FORCEPROP 2 LAST $XR0 46 
J 0
(-8401 5375);
DISPLAY 0.638298 (-8401 5375);
PAINT MONO (-8401 5375);
FORCEPROP 2 LAST CDS_LIB mstr_standard
J 0
(-8150 5375);
DISPLAY 0.723404 (-8150 5375);
PAINT MONO (-8150 5375);
DISPLAY INVISIBLE (-8150 5375);
FORCEPROP 1 LAST OFFPAGE TRUE
J 0
(-7825 5250);
DISPLAY 0.872340 (-7825 5250);
PAINT GREEN (-7825 5250);
DISPLAY INVISIBLE (-7825 5250);
FORCEPROP 1 LAST COMMENT_BODY TRUE
J 0
(-8025 5275);
DISPLAY 0.872340 (-8025 5275);
PAINT GREEN (-8025 5275);
DISPLAY INVISIBLE (-8025 5275);
FORCEPROP 2 LAST PATH I21
J 0
(-8400 5425);
DISPLAY 1.021277 (-8400 5425);
DISPLAY INVISIBLE (-8400 5425);
FORCEADD TAP..1
(-3350 4350);
FORCEPROP 3 LASTPIN (-3400 4350) SIG_NAME M_J_CPU1_SA_DQS_DP<6>
J 0
(-3390 4360);
DISPLAY 0.659574 (-3390 4360);
PAINT MONO (-3390 4360);
DISPLAY INVISIBLE (-3390 4360);
FORCEPROP 1 LASTPIN (-3400 4350) BN 6
J 0
(-3412 4358);
DISPLAY 0.489362 (-3412 4358);
PAINT GREEN (-3412 4358);
FORCEPROP 2 LAST CDS_LIB mstr_standard
J 0
(-3350 4350);
DISPLAY 0.723404 (-3350 4350);
PAINT MONO (-3350 4350);
DISPLAY INVISIBLE (-3350 4350);
FORCEPROP 1 LAST BODY_TYPE PLUMBING
J 0
(-3350 4400);
DISPLAY 0.872340 (-3350 4400);
PAINT GREEN (-3350 4400);
DISPLAY INVISIBLE (-3350 4400);
FORCEPROP 1 LAST HDL_TAP TRUE
J 0
(-3025 4225);
DISPLAY 0.872340 (-3025 4225);
DISPLAY INVISIBLE (-3025 4225);
FORCEPROP 1 LAST PATH I210
J 0
(-3352 4350);
DISPLAY 0.872340 (-3352 4350);
PAINT GREEN (-3352 4350);
DISPLAY INVISIBLE (-3352 4350);
FORCEADD TAP..1
(-3350 4250);
FORCEPROP 3 LASTPIN (-3400 4250) SIG_NAME M_J_CPU1_SA_DQS_DP<5>
J 0
(-3390 4260);
DISPLAY 0.659574 (-3390 4260);
PAINT MONO (-3390 4260);
DISPLAY INVISIBLE (-3390 4260);
FORCEPROP 1 LASTPIN (-3400 4250) BN 5
J 0
(-3412 4258);
DISPLAY 0.489362 (-3412 4258);
PAINT GREEN (-3412 4258);
FORCEPROP 2 LAST CDS_LIB mstr_standard
J 0
(-3350 4250);
DISPLAY 0.723404 (-3350 4250);
PAINT MONO (-3350 4250);
DISPLAY INVISIBLE (-3350 4250);
FORCEPROP 1 LAST BODY_TYPE PLUMBING
J 0
(-3350 4300);
DISPLAY 0.872340 (-3350 4300);
PAINT GREEN (-3350 4300);
DISPLAY INVISIBLE (-3350 4300);
FORCEPROP 1 LAST HDL_TAP TRUE
J 0
(-3025 4125);
DISPLAY 0.872340 (-3025 4125);
DISPLAY INVISIBLE (-3025 4125);
FORCEPROP 1 LAST PATH I211
J 0
(-3352 4250);
DISPLAY 0.872340 (-3352 4250);
PAINT GREEN (-3352 4250);
DISPLAY INVISIBLE (-3352 4250);
FORCEADD TAP..1
(-3350 4050);
FORCEPROP 3 LASTPIN (-3400 4050) SIG_NAME M_J_CPU1_SA_DQS_DP<3>
J 0
(-3390 4060);
DISPLAY 0.659574 (-3390 4060);
PAINT MONO (-3390 4060);
DISPLAY INVISIBLE (-3390 4060);
FORCEPROP 1 LASTPIN (-3400 4050) BN 3
J 0
(-3412 4058);
DISPLAY 0.489362 (-3412 4058);
PAINT GREEN (-3412 4058);
FORCEPROP 2 LAST CDS_LIB mstr_standard
J 0
(-3350 4050);
DISPLAY 0.723404 (-3350 4050);
PAINT MONO (-3350 4050);
DISPLAY INVISIBLE (-3350 4050);
FORCEPROP 1 LAST BODY_TYPE PLUMBING
J 0
(-3350 4100);
DISPLAY 0.872340 (-3350 4100);
PAINT GREEN (-3350 4100);
DISPLAY INVISIBLE (-3350 4100);
FORCEPROP 1 LAST HDL_TAP TRUE
J 0
(-3025 3925);
DISPLAY 0.872340 (-3025 3925);
DISPLAY INVISIBLE (-3025 3925);
FORCEPROP 1 LAST PATH I212
J 0
(-3352 4050);
DISPLAY 0.872340 (-3352 4050);
PAINT GREEN (-3352 4050);
DISPLAY INVISIBLE (-3352 4050);
FORCEADD TAP..1
(-3350 4150);
FORCEPROP 3 LASTPIN (-3400 4150) SIG_NAME M_J_CPU1_SA_DQS_DP<4>
J 0
(-3390 4160);
DISPLAY 0.659574 (-3390 4160);
PAINT MONO (-3390 4160);
DISPLAY INVISIBLE (-3390 4160);
FORCEPROP 1 LASTPIN (-3400 4150) BN 4
J 0
(-3412 4158);
DISPLAY 0.489362 (-3412 4158);
PAINT GREEN (-3412 4158);
FORCEPROP 2 LAST CDS_LIB mstr_standard
J 0
(-3350 4150);
DISPLAY 0.723404 (-3350 4150);
PAINT MONO (-3350 4150);
DISPLAY INVISIBLE (-3350 4150);
FORCEPROP 1 LAST BODY_TYPE PLUMBING
J 0
(-3350 4200);
DISPLAY 0.872340 (-3350 4200);
PAINT GREEN (-3350 4200);
DISPLAY INVISIBLE (-3350 4200);
FORCEPROP 1 LAST HDL_TAP TRUE
J 0
(-3025 4025);
DISPLAY 0.872340 (-3025 4025);
DISPLAY INVISIBLE (-3025 4025);
FORCEPROP 1 LAST PATH I213
J 0
(-3352 4150);
DISPLAY 0.872340 (-3352 4150);
PAINT GREEN (-3352 4150);
DISPLAY INVISIBLE (-3352 4150);
FORCEADD TAP..1
(-3350 3950);
FORCEPROP 3 LASTPIN (-3400 3950) SIG_NAME M_J_CPU1_SA_DQS_DP<2>
J 0
(-3390 3960);
DISPLAY 0.659574 (-3390 3960);
PAINT MONO (-3390 3960);
DISPLAY INVISIBLE (-3390 3960);
FORCEPROP 1 LASTPIN (-3400 3950) BN 2
J 0
(-3412 3958);
DISPLAY 0.489362 (-3412 3958);
PAINT GREEN (-3412 3958);
FORCEPROP 2 LAST CDS_LIB mstr_standard
J 0
(-3350 3950);
DISPLAY 0.723404 (-3350 3950);
PAINT MONO (-3350 3950);
DISPLAY INVISIBLE (-3350 3950);
FORCEPROP 1 LAST BODY_TYPE PLUMBING
J 0
(-3350 4000);
DISPLAY 0.872340 (-3350 4000);
PAINT GREEN (-3350 4000);
DISPLAY INVISIBLE (-3350 4000);
FORCEPROP 1 LAST HDL_TAP TRUE
J 0
(-3025 3825);
DISPLAY 0.872340 (-3025 3825);
DISPLAY INVISIBLE (-3025 3825);
FORCEPROP 1 LAST PATH I214
J 0
(-3352 3950);
DISPLAY 0.872340 (-3352 3950);
PAINT GREEN (-3352 3950);
DISPLAY INVISIBLE (-3352 3950);
FORCEADD TAP..1
(-3350 3850);
FORCEPROP 3 LASTPIN (-3400 3850) SIG_NAME M_J_CPU1_SA_DQS_DP<1>
J 0
(-3390 3860);
DISPLAY 0.659574 (-3390 3860);
PAINT MONO (-3390 3860);
DISPLAY INVISIBLE (-3390 3860);
FORCEPROP 1 LASTPIN (-3400 3850) BN 1
J 0
(-3412 3858);
DISPLAY 0.489362 (-3412 3858);
PAINT GREEN (-3412 3858);
FORCEPROP 2 LAST CDS_LIB mstr_standard
J 0
(-3350 3850);
DISPLAY 0.723404 (-3350 3850);
PAINT MONO (-3350 3850);
DISPLAY INVISIBLE (-3350 3850);
FORCEPROP 1 LAST BODY_TYPE PLUMBING
J 0
(-3350 3900);
DISPLAY 0.872340 (-3350 3900);
PAINT GREEN (-3350 3900);
DISPLAY INVISIBLE (-3350 3900);
FORCEPROP 1 LAST HDL_TAP TRUE
J 0
(-3025 3725);
DISPLAY 0.872340 (-3025 3725);
DISPLAY INVISIBLE (-3025 3725);
FORCEPROP 1 LAST PATH I215
J 0
(-3352 3850);
DISPLAY 0.872340 (-3352 3850);
PAINT GREEN (-3352 3850);
DISPLAY INVISIBLE (-3352 3850);
FORCEADD TAP..1
(-3350 3600);
FORCEPROP 3 LASTPIN (-3400 3600) SIG_NAME M_J_CPU1_SB_DQS_DP<9>
J 0
(-3390 3610);
DISPLAY 0.659574 (-3390 3610);
PAINT MONO (-3390 3610);
DISPLAY INVISIBLE (-3390 3610);
FORCEPROP 1 LASTPIN (-3400 3600) BN 9
J 0
(-3412 3608);
DISPLAY 0.489362 (-3412 3608);
PAINT GREEN (-3412 3608);
FORCEPROP 2 LAST CDS_LIB mstr_standard
J 0
(-3350 3600);
DISPLAY 0.723404 (-3350 3600);
PAINT MONO (-3350 3600);
DISPLAY INVISIBLE (-3350 3600);
FORCEPROP 1 LAST BODY_TYPE PLUMBING
J 0
(-3350 3650);
DISPLAY 0.872340 (-3350 3650);
PAINT GREEN (-3350 3650);
DISPLAY INVISIBLE (-3350 3650);
FORCEPROP 1 LAST HDL_TAP TRUE
J 0
(-3025 3475);
DISPLAY 0.872340 (-3025 3475);
DISPLAY INVISIBLE (-3025 3475);
FORCEPROP 1 LAST PATH I216
J 0
(-3352 3600);
DISPLAY 0.872340 (-3352 3600);
PAINT GREEN (-3352 3600);
DISPLAY INVISIBLE (-3352 3600);
FORCEADD TAP..1
(-3350 3750);
FORCEPROP 3 LASTPIN (-3400 3750) SIG_NAME M_J_CPU1_SA_DQS_DP<0>
J 0
(-3390 3760);
DISPLAY 0.659574 (-3390 3760);
PAINT MONO (-3390 3760);
DISPLAY INVISIBLE (-3390 3760);
FORCEPROP 1 LASTPIN (-3400 3750) BN 0
J 0
(-3412 3758);
DISPLAY 0.489362 (-3412 3758);
PAINT GREEN (-3412 3758);
FORCEPROP 2 LAST CDS_LIB mstr_standard
J 0
(-3350 3750);
DISPLAY 0.723404 (-3350 3750);
PAINT MONO (-3350 3750);
DISPLAY INVISIBLE (-3350 3750);
FORCEPROP 1 LAST BODY_TYPE PLUMBING
J 0
(-3350 3800);
DISPLAY 0.872340 (-3350 3800);
PAINT GREEN (-3350 3800);
DISPLAY INVISIBLE (-3350 3800);
FORCEPROP 1 LAST HDL_TAP TRUE
J 0
(-3025 3625);
DISPLAY 0.872340 (-3025 3625);
DISPLAY INVISIBLE (-3025 3625);
FORCEPROP 1 LAST PATH I217
J 0
(-3352 3750);
DISPLAY 0.872340 (-3352 3750);
PAINT GREEN (-3352 3750);
DISPLAY INVISIBLE (-3352 3750);
FORCEADD TAP..1
(-3150 3450);
FORCEPROP 3 LASTPIN (-3200 3450) SIG_NAME M_J_CPU1_SB_DQS_DN<8>
J 0
(-3190 3460);
DISPLAY 0.659574 (-3190 3460);
PAINT MONO (-3190 3460);
DISPLAY INVISIBLE (-3190 3460);
FORCEPROP 1 LASTPIN (-3200 3450) BN 8
J 0
(-3212 3458);
DISPLAY 0.489362 (-3212 3458);
PAINT GREEN (-3212 3458);
FORCEPROP 2 LAST CDS_LIB mstr_standard
J 0
(-3150 3450);
DISPLAY 0.723404 (-3150 3450);
PAINT MONO (-3150 3450);
DISPLAY INVISIBLE (-3150 3450);
FORCEPROP 1 LAST BODY_TYPE PLUMBING
J 0
(-3150 3500);
DISPLAY 0.872340 (-3150 3500);
PAINT GREEN (-3150 3500);
DISPLAY INVISIBLE (-3150 3500);
FORCEPROP 1 LAST HDL_TAP TRUE
J 0
(-2825 3325);
DISPLAY 0.872340 (-2825 3325);
DISPLAY INVISIBLE (-2825 3325);
FORCEPROP 1 LAST PATH I218
J 0
(-3152 3450);
DISPLAY 0.872340 (-3152 3450);
PAINT GREEN (-3152 3450);
DISPLAY INVISIBLE (-3152 3450);
FORCEADD TAP..1
(-3150 3350);
FORCEPROP 3 LASTPIN (-3200 3350) SIG_NAME M_J_CPU1_SB_DQS_DN<7>
J 0
(-3190 3360);
DISPLAY 0.659574 (-3190 3360);
PAINT MONO (-3190 3360);
DISPLAY INVISIBLE (-3190 3360);
FORCEPROP 1 LASTPIN (-3200 3350) BN 7
J 0
(-3212 3358);
DISPLAY 0.489362 (-3212 3358);
PAINT GREEN (-3212 3358);
FORCEPROP 2 LAST CDS_LIB mstr_standard
J 0
(-3150 3350);
DISPLAY 0.723404 (-3150 3350);
PAINT MONO (-3150 3350);
DISPLAY INVISIBLE (-3150 3350);
FORCEPROP 1 LAST BODY_TYPE PLUMBING
J 0
(-3150 3400);
DISPLAY 0.872340 (-3150 3400);
PAINT GREEN (-3150 3400);
DISPLAY INVISIBLE (-3150 3400);
FORCEPROP 1 LAST HDL_TAP TRUE
J 0
(-2825 3225);
DISPLAY 0.872340 (-2825 3225);
DISPLAY INVISIBLE (-2825 3225);
FORCEPROP 1 LAST PATH I219
J 0
(-3152 3350);
DISPLAY 0.872340 (-3152 3350);
PAINT GREEN (-3152 3350);
DISPLAY INVISIBLE (-3152 3350);
FORCEADD SCONN288_DDR506112002KQ..1
(-6700 3575);
FORCEPROP 1 LAST LOCATION J29
J 0
(-7150 5650);
DISPLAY 0.468085 (-7150 5650);
PAINT SKYBLUE (-7150 5650);
FORCEPROP 0 LAST $SEC 1
J 0
(-7150 5800);
DISPLAY 0.680851 (-7150 5800);
PAINT MONO (-7150 5800);
DISPLAY INVISIBLE (-7150 5800);
FORCEPROP 2 LAST CDS_SEC 1
J 0
(-7150 5800);
DISPLAY 1.021277 (-7150 5800);
DISPLAY INVISIBLE (-7150 5800);
FORCEPROP 0 LASTPIN (-7300 2975) $PN 62
J 2
(-7310 2985);
DISPLAY 0.680851 (-7310 2985);
PAINT MONO (-7310 2985);
FORCEPROP 0 LASTPIN (-7300 5025) $PN 66
J 2
(-7310 5035);
DISPLAY 0.680851 (-7310 5035);
PAINT MONO (-7310 5035);
FORCEPROP 0 LASTPIN (-7300 4625) $PN 76
J 2
(-7310 4635);
DISPLAY 0.680851 (-7310 4635);
PAINT MONO (-7310 4635);
FORCEPROP 0 LASTPIN (-7300 5075) $PN 211
J 2
(-7310 5085);
DISPLAY 0.680851 (-7310 5085);
PAINT MONO (-7310 5085);
FORCEPROP 0 LASTPIN (-7300 4675) $PN 221
J 2
(-7310 4685);
DISPLAY 0.680851 (-7310 4685);
PAINT MONO (-7310 4685);
FORCEPROP 0 LASTPIN (-7300 5125) $PN 68
J 2
(-7310 5135);
DISPLAY 0.680851 (-7310 5135);
PAINT MONO (-7310 5135);
FORCEPROP 0 LASTPIN (-7300 4725) $PN 78
J 2
(-7310 4735);
DISPLAY 0.680851 (-7310 4735);
PAINT MONO (-7310 4735);
FORCEPROP 0 LASTPIN (-7300 5175) $PN 213
J 2
(-7310 5185);
DISPLAY 0.680851 (-7310 5185);
PAINT MONO (-7310 5185);
FORCEPROP 0 LASTPIN (-7300 4775) $PN 223
J 2
(-7310 4785);
DISPLAY 0.680851 (-7310 4785);
PAINT MONO (-7310 4785);
FORCEPROP 0 LASTPIN (-7300 5225) $PN 70
J 2
(-7310 5235);
DISPLAY 0.680851 (-7310 5235);
PAINT MONO (-7310 5235);
FORCEPROP 0 LASTPIN (-7300 4825) $PN 80
J 2
(-7310 4835);
DISPLAY 0.680851 (-7310 4835);
PAINT MONO (-7310 4835);
FORCEPROP 0 LASTPIN (-7300 5275) $PN 215
J 2
(-7310 5285);
DISPLAY 0.680851 (-7310 5285);
PAINT MONO (-7310 5285);
FORCEPROP 0 LASTPIN (-7300 4875) $PN 225
J 2
(-7310 4885);
DISPLAY 0.680851 (-7310 4885);
PAINT MONO (-7310 4885);
FORCEPROP 0 LASTPIN (-7300 5325) $PN 72
J 2
(-7310 5335);
DISPLAY 0.680851 (-7310 5335);
PAINT MONO (-7310 5335);
FORCEPROP 0 LASTPIN (-7300 4925) $PN 82
J 2
(-7310 4935);
DISPLAY 0.680851 (-7310 4935);
PAINT MONO (-7310 4935);
FORCEPROP 0 LASTPIN (-7300 3575) $PN 51
J 2
(-7310 3585);
DISPLAY 0.680851 (-7310 3585);
PAINT MONO (-7310 3585);
FORCEPROP 0 LASTPIN (-7300 3125) $PN 96
J 2
(-7310 3135);
DISPLAY 0.680851 (-7310 3135);
PAINT MONO (-7310 3135);
FORCEPROP 0 LASTPIN (-7300 3625) $PN 53
J 2
(-7310 3635);
DISPLAY 0.680851 (-7310 3635);
PAINT MONO (-7310 3635);
FORCEPROP 0 LASTPIN (-7300 3175) $PN 98
J 2
(-7310 3185);
DISPLAY 0.680851 (-7310 3185);
PAINT MONO (-7310 3185);
FORCEPROP 0 LASTPIN (-7300 3675) $PN 196
J 2
(-7310 3685);
DISPLAY 0.680851 (-7310 3685);
PAINT MONO (-7310 3685);
FORCEPROP 0 LASTPIN (-7300 3225) $PN 241
J 2
(-7310 3235);
DISPLAY 0.680851 (-7310 3235);
PAINT MONO (-7310 3235);
FORCEPROP 0 LASTPIN (-7300 3725) $PN 198
J 2
(-7310 3735);
DISPLAY 0.680851 (-7310 3735);
PAINT MONO (-7310 3735);
FORCEPROP 0 LASTPIN (-7300 3275) $PN 243
J 2
(-7310 3285);
DISPLAY 0.680851 (-7310 3285);
PAINT MONO (-7310 3285);
FORCEPROP 0 LASTPIN (-7300 3775) $PN 58
J 2
(-7310 3785);
DISPLAY 0.680851 (-7310 3785);
PAINT MONO (-7310 3785);
FORCEPROP 0 LASTPIN (-7300 3325) $PN 89
J 2
(-7310 3335);
DISPLAY 0.680851 (-7310 3335);
PAINT MONO (-7310 3335);
FORCEPROP 0 LASTPIN (-7300 3825) $PN 60
J 2
(-7310 3835);
DISPLAY 0.680851 (-7310 3835);
PAINT MONO (-7310 3835);
FORCEPROP 0 LASTPIN (-7300 3375) $PN 91
J 2
(-7310 3385);
DISPLAY 0.680851 (-7310 3385);
PAINT MONO (-7310 3385);
FORCEPROP 0 LASTPIN (-7300 3875) $PN 203
J 2
(-7310 3885);
DISPLAY 0.680851 (-7310 3885);
PAINT MONO (-7310 3885);
FORCEPROP 0 LASTPIN (-7300 3425) $PN 234
J 2
(-7310 3435);
DISPLAY 0.680851 (-7310 3435);
PAINT MONO (-7310 3435);
FORCEPROP 0 LASTPIN (-7300 3925) $PN 205
J 2
(-7310 3935);
DISPLAY 0.680851 (-7310 3935);
PAINT MONO (-7310 3935);
FORCEPROP 0 LASTPIN (-7300 3475) $PN 236
J 2
(-7310 3485);
DISPLAY 0.680851 (-7310 3485);
PAINT MONO (-7310 3485);
FORCEPROP 0 LASTPIN (-7300 4025) $PN 218
J 2
(-7310 4035);
DISPLAY 0.680851 (-7310 4035);
PAINT MONO (-7310 4035);
FORCEPROP 0 LASTPIN (-7300 4075) $PN 217
J 2
(-7310 4085);
DISPLAY 0.680851 (-7310 4085);
PAINT MONO (-7310 4085);
FORCEPROP 0 LASTPIN (-7300 4325) $PN 64
J 2
(-7310 4335);
DISPLAY 0.680851 (-7310 4335);
PAINT MONO (-7310 4335);
FORCEPROP 0 LASTPIN (-7300 4175) $PN 84
J 2
(-7310 4185);
DISPLAY 0.680851 (-7310 4185);
PAINT MONO (-7310 4185);
FORCEPROP 0 LASTPIN (-7300 4375) $PN 209
J 2
(-7310 4385);
DISPLAY 0.680851 (-7310 4385);
PAINT MONO (-7310 4385);
FORCEPROP 0 LASTPIN (-7300 4225) $PN 229
J 2
(-7310 4235);
DISPLAY 0.680851 (-7310 4235);
PAINT MONO (-7310 4235);
FORCEPROP 0 LASTPIN (-6100 3775) $PN 7
J 0
(-6090 3785);
DISPLAY 0.680851 (-6090 3785);
PAINT MONO (-6090 3785);
FORCEPROP 0 LASTPIN (-6100 2125) $PN 100
J 0
(-6090 2135);
DISPLAY 0.680851 (-6090 2135);
PAINT MONO (-6090 2135);
FORCEPROP 0 LASTPIN (-6100 3825) $PN 9
J 0
(-6090 3835);
DISPLAY 0.680851 (-6090 3835);
PAINT MONO (-6090 3835);
FORCEPROP 0 LASTPIN (-6100 2175) $PN 102
J 0
(-6090 2185);
DISPLAY 0.680851 (-6090 2185);
PAINT MONO (-6090 2185);
FORCEPROP 0 LASTPIN (-6100 3875) $PN 152
J 0
(-6090 3885);
DISPLAY 0.680851 (-6090 3885);
PAINT MONO (-6090 3885);
FORCEPROP 0 LASTPIN (-6100 2225) $PN 245
J 0
(-6090 2235);
DISPLAY 0.680851 (-6090 2235);
PAINT MONO (-6090 2235);
FORCEPROP 0 LASTPIN (-6100 3925) $PN 154
J 0
(-6090 3935);
DISPLAY 0.680851 (-6090 3935);
PAINT MONO (-6090 3935);
FORCEPROP 0 LASTPIN (-6100 2275) $PN 247
J 0
(-6090 2285);
DISPLAY 0.680851 (-6090 2285);
PAINT MONO (-6090 2285);
FORCEPROP 0 LASTPIN (-6100 3975) $PN 14
J 0
(-6090 3985);
DISPLAY 0.680851 (-6090 3985);
PAINT MONO (-6090 3985);
FORCEPROP 0 LASTPIN (-6100 2325) $PN 107
J 0
(-6090 2335);
DISPLAY 0.680851 (-6090 2335);
PAINT MONO (-6090 2335);
FORCEPROP 0 LASTPIN (-6100 4025) $PN 16
J 0
(-6090 4035);
DISPLAY 0.680851 (-6090 4035);
PAINT MONO (-6090 4035);
FORCEPROP 0 LASTPIN (-6100 2375) $PN 109
J 0
(-6090 2385);
DISPLAY 0.680851 (-6090 2385);
PAINT MONO (-6090 2385);
FORCEPROP 0 LASTPIN (-6100 4075) $PN 159
J 0
(-6090 4085);
DISPLAY 0.680851 (-6090 4085);
PAINT MONO (-6090 4085);
FORCEPROP 0 LASTPIN (-6100 2425) $PN 252
J 0
(-6090 2435);
DISPLAY 0.680851 (-6090 2435);
PAINT MONO (-6090 2435);
FORCEPROP 0 LASTPIN (-6100 4125) $PN 161
J 0
(-6090 4135);
DISPLAY 0.680851 (-6090 4135);
PAINT MONO (-6090 4135);
FORCEPROP 0 LASTPIN (-6100 2475) $PN 254
J 0
(-6090 2485);
DISPLAY 0.680851 (-6090 2485);
PAINT MONO (-6090 2485);
FORCEPROP 0 LASTPIN (-6100 4175) $PN 18
J 0
(-6090 4185);
DISPLAY 0.680851 (-6090 4185);
PAINT MONO (-6090 4185);
FORCEPROP 0 LASTPIN (-6100 2525) $PN 111
J 0
(-6090 2535);
DISPLAY 0.680851 (-6090 2535);
PAINT MONO (-6090 2535);
FORCEPROP 0 LASTPIN (-6100 4225) $PN 20
J 0
(-6090 4235);
DISPLAY 0.680851 (-6090 4235);
PAINT MONO (-6090 4235);
FORCEPROP 0 LASTPIN (-6100 2575) $PN 113
J 0
(-6090 2585);
DISPLAY 0.680851 (-6090 2585);
PAINT MONO (-6090 2585);
FORCEPROP 0 LASTPIN (-6100 4275) $PN 163
J 0
(-6090 4285);
DISPLAY 0.680851 (-6090 4285);
PAINT MONO (-6090 4285);
FORCEPROP 0 LASTPIN (-6100 2625) $PN 256
J 0
(-6090 2635);
DISPLAY 0.680851 (-6090 2635);
PAINT MONO (-6090 2635);
FORCEPROP 0 LASTPIN (-6100 4325) $PN 165
J 0
(-6090 4335);
DISPLAY 0.680851 (-6090 4335);
PAINT MONO (-6090 4335);
FORCEPROP 0 LASTPIN (-6100 2675) $PN 258
J 0
(-6090 2685);
DISPLAY 0.680851 (-6090 2685);
PAINT MONO (-6090 2685);
FORCEPROP 0 LASTPIN (-6100 4375) $PN 25
J 0
(-6090 4385);
DISPLAY 0.680851 (-6090 4385);
PAINT MONO (-6090 4385);
FORCEPROP 0 LASTPIN (-6100 2725) $PN 118
J 0
(-6090 2735);
DISPLAY 0.680851 (-6090 2735);
PAINT MONO (-6090 2735);
FORCEPROP 0 LASTPIN (-6100 4425) $PN 27
J 0
(-6090 4435);
DISPLAY 0.680851 (-6090 4435);
PAINT MONO (-6090 4435);
FORCEPROP 0 LASTPIN (-6100 2775) $PN 120
J 0
(-6090 2785);
DISPLAY 0.680851 (-6090 2785);
PAINT MONO (-6090 2785);
FORCEPROP 0 LASTPIN (-6100 4475) $PN 170
J 0
(-6090 4485);
DISPLAY 0.680851 (-6090 4485);
PAINT MONO (-6090 4485);
FORCEPROP 0 LASTPIN (-6100 2825) $PN 263
J 0
(-6090 2835);
DISPLAY 0.680851 (-6090 2835);
PAINT MONO (-6090 2835);
FORCEPROP 0 LASTPIN (-6100 4525) $PN 172
J 0
(-6090 4535);
DISPLAY 0.680851 (-6090 4535);
PAINT MONO (-6090 4535);
FORCEPROP 0 LASTPIN (-6100 2875) $PN 265
J 0
(-6090 2885);
DISPLAY 0.680851 (-6090 2885);
PAINT MONO (-6090 2885);
FORCEPROP 0 LASTPIN (-6100 4575) $PN 29
J 0
(-6090 4585);
DISPLAY 0.680851 (-6090 4585);
PAINT MONO (-6090 4585);
FORCEPROP 0 LASTPIN (-6100 2925) $PN 122
J 0
(-6090 2935);
DISPLAY 0.680851 (-6090 2935);
PAINT MONO (-6090 2935);
FORCEPROP 0 LASTPIN (-6100 4625) $PN 31
J 0
(-6090 4635);
DISPLAY 0.680851 (-6090 4635);
PAINT MONO (-6090 4635);
FORCEPROP 0 LASTPIN (-6100 2975) $PN 124
J 0
(-6090 2985);
DISPLAY 0.680851 (-6090 2985);
PAINT MONO (-6090 2985);
FORCEPROP 0 LASTPIN (-6100 4675) $PN 174
J 0
(-6090 4685);
DISPLAY 0.680851 (-6090 4685);
PAINT MONO (-6090 4685);
FORCEPROP 0 LASTPIN (-6100 3025) $PN 267
J 0
(-6090 3035);
DISPLAY 0.680851 (-6090 3035);
PAINT MONO (-6090 3035);
FORCEPROP 0 LASTPIN (-6100 4725) $PN 176
J 0
(-6090 4735);
DISPLAY 0.680851 (-6090 4735);
PAINT MONO (-6090 4735);
FORCEPROP 0 LASTPIN (-6100 3075) $PN 269
J 0
(-6090 3085);
DISPLAY 0.680851 (-6090 3085);
PAINT MONO (-6090 3085);
FORCEPROP 0 LASTPIN (-6100 4775) $PN 36
J 0
(-6090 4785);
DISPLAY 0.680851 (-6090 4785);
PAINT MONO (-6090 4785);
FORCEPROP 0 LASTPIN (-6100 3125) $PN 129
J 0
(-6090 3135);
DISPLAY 0.680851 (-6090 3135);
PAINT MONO (-6090 3135);
FORCEPROP 0 LASTPIN (-6100 4825) $PN 38
J 0
(-6090 4835);
DISPLAY 0.680851 (-6090 4835);
PAINT MONO (-6090 4835);
FORCEPROP 0 LASTPIN (-6100 3175) $PN 131
J 0
(-6090 3185);
DISPLAY 0.680851 (-6090 3185);
PAINT MONO (-6090 3185);
FORCEPROP 0 LASTPIN (-6100 4875) $PN 181
J 0
(-6090 4885);
DISPLAY 0.680851 (-6090 4885);
PAINT MONO (-6090 4885);
FORCEPROP 0 LASTPIN (-6100 3225) $PN 274
J 0
(-6090 3235);
DISPLAY 0.680851 (-6090 3235);
PAINT MONO (-6090 3235);
FORCEPROP 0 LASTPIN (-6100 4925) $PN 183
J 0
(-6090 4935);
DISPLAY 0.680851 (-6090 4935);
PAINT MONO (-6090 4935);
FORCEPROP 0 LASTPIN (-6100 3275) $PN 276
J 0
(-6090 3285);
DISPLAY 0.680851 (-6090 3285);
PAINT MONO (-6090 3285);
FORCEPROP 0 LASTPIN (-6100 4975) $PN 40
J 0
(-6090 4985);
DISPLAY 0.680851 (-6090 4985);
PAINT MONO (-6090 4985);
FORCEPROP 0 LASTPIN (-6100 3325) $PN 133
J 0
(-6090 3335);
DISPLAY 0.680851 (-6090 3335);
PAINT MONO (-6090 3335);
FORCEPROP 0 LASTPIN (-6100 5025) $PN 42
J 0
(-6090 5035);
DISPLAY 0.680851 (-6090 5035);
PAINT MONO (-6090 5035);
FORCEPROP 0 LASTPIN (-6100 3375) $PN 135
J 0
(-6090 3385);
DISPLAY 0.680851 (-6090 3385);
PAINT MONO (-6090 3385);
FORCEPROP 0 LASTPIN (-6100 5075) $PN 185
J 0
(-6090 5085);
DISPLAY 0.680851 (-6090 5085);
PAINT MONO (-6090 5085);
FORCEPROP 0 LASTPIN (-6100 3425) $PN 278
J 0
(-6090 3435);
DISPLAY 0.680851 (-6090 3435);
PAINT MONO (-6090 3435);
FORCEPROP 0 LASTPIN (-6100 5125) $PN 187
J 0
(-6090 5135);
DISPLAY 0.680851 (-6090 5135);
PAINT MONO (-6090 5135);
FORCEPROP 0 LASTPIN (-6100 3475) $PN 280
J 0
(-6090 3485);
DISPLAY 0.680851 (-6090 3485);
PAINT MONO (-6090 3485);
FORCEPROP 0 LASTPIN (-6100 5175) $PN 47
J 0
(-6090 5185);
DISPLAY 0.680851 (-6090 5185);
PAINT MONO (-6090 5185);
FORCEPROP 0 LASTPIN (-6100 3525) $PN 140
J 0
(-6090 3535);
DISPLAY 0.680851 (-6090 3535);
PAINT MONO (-6090 3535);
FORCEPROP 0 LASTPIN (-6100 5225) $PN 49
J 0
(-6090 5235);
DISPLAY 0.680851 (-6090 5235);
PAINT MONO (-6090 5235);
FORCEPROP 0 LASTPIN (-6100 3575) $PN 142
J 0
(-6090 3585);
DISPLAY 0.680851 (-6090 3585);
PAINT MONO (-6090 3585);
FORCEPROP 0 LASTPIN (-6100 5275) $PN 192
J 0
(-6090 5285);
DISPLAY 0.680851 (-6090 5285);
PAINT MONO (-6090 5285);
FORCEPROP 0 LASTPIN (-6100 3625) $PN 285
J 0
(-6090 3635);
DISPLAY 0.680851 (-6090 3635);
PAINT MONO (-6090 3635);
FORCEPROP 0 LASTPIN (-6100 5325) $PN 194
J 0
(-6090 5335);
DISPLAY 0.680851 (-6090 5335);
PAINT MONO (-6090 5335);
FORCEPROP 0 LASTPIN (-6100 3675) $PN 287
J 0
(-6090 3685);
DISPLAY 0.680851 (-6090 3685);
PAINT MONO (-6090 3685);
FORCEPROP 0 LASTPIN (-7300 2825) $PN 148
J 2
(-7310 2835);
DISPLAY 0.680851 (-7310 2835);
PAINT MONO (-7310 2835);
FORCEPROP 0 LASTPIN (-7300 2725) $PN 4
J 2
(-7310 2735);
DISPLAY 0.680851 (-7310 2735);
PAINT MONO (-7310 2735);
FORCEPROP 0 LASTPIN (-7300 2775) $PN 5
J 2
(-7310 2785);
DISPLAY 0.680851 (-7310 2785);
PAINT MONO (-7310 2785);
FORCEPROP 0 LASTPIN (-7300 1925) $PN 86
J 2
(-7310 1935);
DISPLAY 0.680851 (-7310 1935);
PAINT MONO (-7310 1935);
FORCEPROP 0 LASTPIN (-7300 1875) $PN 87
J 2
(-7310 1885);
DISPLAY 0.680851 (-7310 1885);
PAINT MONO (-7310 1885);
FORCEPROP 0 LASTPIN (-7300 4525) $PN 74
J 2
(-7310 4535);
DISPLAY 0.680851 (-7310 4535);
PAINT MONO (-7310 4535);
FORCEPROP 0 LASTPIN (-7300 4475) $PN 227
J 2
(-7310 4485);
DISPLAY 0.680851 (-7310 4485);
PAINT MONO (-7310 4485);
FORCEPROP 0 LASTPIN (-7300 2475) $PN 147
J 2
(-7310 2485);
DISPLAY 0.680851 (-7310 2485);
PAINT MONO (-7310 2485);
FORCEPROP 0 LASTPIN (-7300 3025) $PN 207
J 2
(-7310 3035);
DISPLAY 0.680851 (-7310 3035);
PAINT MONO (-7310 3035);
FORCEPROP 0 LASTPIN (-7300 2075) $PN 2
J 2
(-7310 2085);
DISPLAY 0.680851 (-7310 2085);
PAINT MONO (-7310 2085);
FORCEPROP 0 LASTPIN (-7300 2125) $PN 144
J 2
(-7310 2135);
DISPLAY 0.680851 (-7310 2135);
PAINT MONO (-7310 2135);
FORCEPROP 0 LASTPIN (-7300 2175) $PN 149
J 2
(-7310 2185);
DISPLAY 0.680851 (-7310 2185);
PAINT MONO (-7310 2185);
FORCEPROP 0 LASTPIN (-7300 2225) $PN 150
J 2
(-7310 2235);
DISPLAY 0.680851 (-7310 2235);
PAINT MONO (-7310 2235);
FORCEPROP 0 LASTPIN (-7300 2275) $PN 220
J 2
(-7310 2285);
DISPLAY 0.680851 (-7310 2285);
PAINT MONO (-7310 2285);
FORCEPROP 0 LASTPIN (-7300 2325) $PN 231
J 2
(-7310 2335);
DISPLAY 0.680851 (-7310 2335);
PAINT MONO (-7310 2335);
FORCEPROP 0 LASTPIN (-7300 2375) $PN 232
J 2
(-7310 2385);
DISPLAY 0.680851 (-7310 2385);
PAINT MONO (-7310 2385);
FORCEPROP 0 LASTPIN (-7300 2875) $PN 3
J 2
(-7310 2885);
DISPLAY 0.680851 (-7310 2885);
PAINT MONO (-7310 2885);
FORCEPROP 1 LAST MATERIAL IO
J 0
(-7150 5500);
DISPLAY 0.468085 (-7150 5500);
PAINT SKYBLUE (-7150 5500);
FORCEPROP 2 LAST VALUE SCONN288_DDR506112002KQ
J 0
(-7150 5700);
DISPLAY 0.489362 (-7150 5700);
PAINT SKYBLUE (-7150 5700);
FORCEPROP 2 LAST PART_TYPE SMLF
J 0
(-7150 5750);
DISPLAY 1.021277 (-7150 5750);
FORCEPROP 2 LAST CDS_LIB pure_quanta
J 0
(-6700 3575);
DISPLAY INVISIBLE (-6700 3575);
FORCEPROP 1 LAST NEEDS_NO_SIZE TRUE
J 0
(-6700 3575);
DISPLAY 0.723404 (-6700 3575);
PAINT GREEN (-6700 3575);
DISPLAY INVISIBLE (-6700 3575);
FORCEPROP 1 LAST CDS_LMAN_SYM_OUTLINE -450,1900,450,-1850
J 0
(-6700 3575);
DISPLAY 0.468085 (-6700 3575);
PAINT GREEN (-6700 3575);
DISPLAY INVISIBLE (-6700 3575);
FORCEPROP 1 LAST PATH I22
J 0
(-6700 3575);
DISPLAY 0.723404 (-6700 3575);
PAINT GREEN (-6700 3575);
DISPLAY INVISIBLE (-6700 3575);
FORCEPROP 1 LAST PART_NUMBER DFHST8FS479
J 0
(-7150 5575);
DISPLAY 0.468085 (-7150 5575);
PAINT SKYBLUE (-7150 5575);
DISPLAY INVISIBLE (-7150 5575);
FORCEADD TAP..1
(-3150 3150);
FORCEPROP 3 LASTPIN (-3200 3150) SIG_NAME M_J_CPU1_SB_DQS_DN<5>
J 0
(-3190 3160);
DISPLAY 0.659574 (-3190 3160);
PAINT MONO (-3190 3160);
DISPLAY INVISIBLE (-3190 3160);
FORCEPROP 1 LASTPIN (-3200 3150) BN 5
J 0
(-3212 3158);
DISPLAY 0.489362 (-3212 3158);
PAINT GREEN (-3212 3158);
FORCEPROP 2 LAST CDS_LIB mstr_standard
J 0
(-3150 3150);
DISPLAY 0.723404 (-3150 3150);
PAINT MONO (-3150 3150);
DISPLAY INVISIBLE (-3150 3150);
FORCEPROP 1 LAST BODY_TYPE PLUMBING
J 0
(-3150 3200);
DISPLAY 0.872340 (-3150 3200);
PAINT GREEN (-3150 3200);
DISPLAY INVISIBLE (-3150 3200);
FORCEPROP 1 LAST HDL_TAP TRUE
J 0
(-2825 3025);
DISPLAY 0.872340 (-2825 3025);
DISPLAY INVISIBLE (-2825 3025);
FORCEPROP 1 LAST PATH I220
J 0
(-3152 3150);
DISPLAY 0.872340 (-3152 3150);
PAINT GREEN (-3152 3150);
DISPLAY INVISIBLE (-3152 3150);
FORCEADD TAP..1
(-3150 3250);
FORCEPROP 3 LASTPIN (-3200 3250) SIG_NAME M_J_CPU1_SB_DQS_DN<6>
J 0
(-3190 3260);
DISPLAY 0.659574 (-3190 3260);
PAINT MONO (-3190 3260);
DISPLAY INVISIBLE (-3190 3260);
FORCEPROP 1 LASTPIN (-3200 3250) BN 6
J 0
(-3212 3258);
DISPLAY 0.489362 (-3212 3258);
PAINT GREEN (-3212 3258);
FORCEPROP 2 LAST CDS_LIB mstr_standard
J 0
(-3150 3250);
DISPLAY 0.723404 (-3150 3250);
PAINT MONO (-3150 3250);
DISPLAY INVISIBLE (-3150 3250);
FORCEPROP 1 LAST BODY_TYPE PLUMBING
J 0
(-3150 3300);
DISPLAY 0.872340 (-3150 3300);
PAINT GREEN (-3150 3300);
DISPLAY INVISIBLE (-3150 3300);
FORCEPROP 1 LAST HDL_TAP TRUE
J 0
(-2825 3125);
DISPLAY 0.872340 (-2825 3125);
DISPLAY INVISIBLE (-2825 3125);
FORCEPROP 1 LAST PATH I221
J 0
(-3152 3250);
DISPLAY 0.872340 (-3152 3250);
PAINT GREEN (-3152 3250);
DISPLAY INVISIBLE (-3152 3250);
FORCEADD TAP..1
(-3150 3050);
FORCEPROP 3 LASTPIN (-3200 3050) SIG_NAME M_J_CPU1_SB_DQS_DN<4>
J 0
(-3190 3060);
DISPLAY 0.659574 (-3190 3060);
PAINT MONO (-3190 3060);
DISPLAY INVISIBLE (-3190 3060);
FORCEPROP 1 LASTPIN (-3200 3050) BN 4
J 0
(-3212 3058);
DISPLAY 0.489362 (-3212 3058);
PAINT GREEN (-3212 3058);
FORCEPROP 2 LAST CDS_LIB mstr_standard
J 0
(-3150 3050);
DISPLAY 0.723404 (-3150 3050);
PAINT MONO (-3150 3050);
DISPLAY INVISIBLE (-3150 3050);
FORCEPROP 1 LAST BODY_TYPE PLUMBING
J 0
(-3150 3100);
DISPLAY 0.872340 (-3150 3100);
PAINT GREEN (-3150 3100);
DISPLAY INVISIBLE (-3150 3100);
FORCEPROP 1 LAST HDL_TAP TRUE
J 0
(-2825 2925);
DISPLAY 0.872340 (-2825 2925);
DISPLAY INVISIBLE (-2825 2925);
FORCEPROP 1 LAST PATH I222
J 0
(-3152 3050);
DISPLAY 0.872340 (-3152 3050);
PAINT GREEN (-3152 3050);
DISPLAY INVISIBLE (-3152 3050);
FORCEADD TAP..1
(-3150 2950);
FORCEPROP 3 LASTPIN (-3200 2950) SIG_NAME M_J_CPU1_SB_DQS_DN<3>
J 0
(-3190 2960);
DISPLAY 0.659574 (-3190 2960);
PAINT MONO (-3190 2960);
DISPLAY INVISIBLE (-3190 2960);
FORCEPROP 1 LASTPIN (-3200 2950) BN 3
J 0
(-3212 2958);
DISPLAY 0.489362 (-3212 2958);
PAINT GREEN (-3212 2958);
FORCEPROP 2 LAST CDS_LIB mstr_standard
J 0
(-3150 2950);
DISPLAY 0.723404 (-3150 2950);
PAINT MONO (-3150 2950);
DISPLAY INVISIBLE (-3150 2950);
FORCEPROP 1 LAST BODY_TYPE PLUMBING
J 0
(-3150 3000);
DISPLAY 0.872340 (-3150 3000);
PAINT GREEN (-3150 3000);
DISPLAY INVISIBLE (-3150 3000);
FORCEPROP 1 LAST HDL_TAP TRUE
J 0
(-2825 2825);
DISPLAY 0.872340 (-2825 2825);
DISPLAY INVISIBLE (-2825 2825);
FORCEPROP 1 LAST PATH I223
J 0
(-3152 2950);
DISPLAY 0.872340 (-3152 2950);
PAINT GREEN (-3152 2950);
DISPLAY INVISIBLE (-3152 2950);
FORCEADD TAP..1
(-3150 2850);
FORCEPROP 3 LASTPIN (-3200 2850) SIG_NAME M_J_CPU1_SB_DQS_DN<2>
J 0
(-3190 2860);
DISPLAY 0.659574 (-3190 2860);
PAINT MONO (-3190 2860);
DISPLAY INVISIBLE (-3190 2860);
FORCEPROP 1 LASTPIN (-3200 2850) BN 2
J 0
(-3212 2858);
DISPLAY 0.489362 (-3212 2858);
PAINT GREEN (-3212 2858);
FORCEPROP 2 LAST CDS_LIB mstr_standard
J 0
(-3150 2850);
DISPLAY 0.723404 (-3150 2850);
PAINT MONO (-3150 2850);
DISPLAY INVISIBLE (-3150 2850);
FORCEPROP 1 LAST BODY_TYPE PLUMBING
J 0
(-3150 2900);
DISPLAY 0.872340 (-3150 2900);
PAINT GREEN (-3150 2900);
DISPLAY INVISIBLE (-3150 2900);
FORCEPROP 1 LAST HDL_TAP TRUE
J 0
(-2825 2725);
DISPLAY 0.872340 (-2825 2725);
DISPLAY INVISIBLE (-2825 2725);
FORCEPROP 1 LAST PATH I224
J 0
(-3152 2850);
DISPLAY 0.872340 (-3152 2850);
PAINT GREEN (-3152 2850);
DISPLAY INVISIBLE (-3152 2850);
FORCEADD TAP..1
(-3150 2750);
FORCEPROP 3 LASTPIN (-3200 2750) SIG_NAME M_J_CPU1_SB_DQS_DN<1>
J 0
(-3190 2760);
DISPLAY 0.659574 (-3190 2760);
PAINT MONO (-3190 2760);
DISPLAY INVISIBLE (-3190 2760);
FORCEPROP 1 LASTPIN (-3200 2750) BN 1
J 0
(-3212 2758);
DISPLAY 0.489362 (-3212 2758);
PAINT GREEN (-3212 2758);
FORCEPROP 2 LAST CDS_LIB mstr_standard
J 0
(-3150 2750);
DISPLAY 0.723404 (-3150 2750);
PAINT MONO (-3150 2750);
DISPLAY INVISIBLE (-3150 2750);
FORCEPROP 1 LAST BODY_TYPE PLUMBING
J 0
(-3150 2800);
DISPLAY 0.872340 (-3150 2800);
PAINT GREEN (-3150 2800);
DISPLAY INVISIBLE (-3150 2800);
FORCEPROP 1 LAST HDL_TAP TRUE
J 0
(-2825 2625);
DISPLAY 0.872340 (-2825 2625);
DISPLAY INVISIBLE (-2825 2625);
FORCEPROP 1 LAST PATH I225
J 0
(-3152 2750);
DISPLAY 0.872340 (-3152 2750);
PAINT GREEN (-3152 2750);
DISPLAY INVISIBLE (-3152 2750);
FORCEADD TAP..1
(-3150 2650);
FORCEPROP 3 LASTPIN (-3200 2650) SIG_NAME M_J_CPU1_SB_DQS_DN<0>
J 0
(-3190 2660);
DISPLAY 0.659574 (-3190 2660);
PAINT MONO (-3190 2660);
DISPLAY INVISIBLE (-3190 2660);
FORCEPROP 1 LASTPIN (-3200 2650) BN 0
J 0
(-3212 2658);
DISPLAY 0.489362 (-3212 2658);
PAINT GREEN (-3212 2658);
FORCEPROP 2 LAST CDS_LIB mstr_standard
J 0
(-3150 2650);
DISPLAY 0.723404 (-3150 2650);
PAINT MONO (-3150 2650);
DISPLAY INVISIBLE (-3150 2650);
FORCEPROP 1 LAST BODY_TYPE PLUMBING
J 0
(-3150 2700);
DISPLAY 0.872340 (-3150 2700);
PAINT GREEN (-3150 2700);
DISPLAY INVISIBLE (-3150 2700);
FORCEPROP 1 LAST HDL_TAP TRUE
J 0
(-2825 2525);
DISPLAY 0.872340 (-2825 2525);
DISPLAY INVISIBLE (-2825 2525);
FORCEPROP 1 LAST PATH I226
J 0
(-3152 2650);
DISPLAY 0.872340 (-3152 2650);
PAINT GREEN (-3152 2650);
DISPLAY INVISIBLE (-3152 2650);
FORCEADD TAP..1
(-3350 3500);
FORCEPROP 3 LASTPIN (-3400 3500) SIG_NAME M_J_CPU1_SB_DQS_DP<8>
J 0
(-3390 3510);
DISPLAY 0.659574 (-3390 3510);
PAINT MONO (-3390 3510);
DISPLAY INVISIBLE (-3390 3510);
FORCEPROP 1 LASTPIN (-3400 3500) BN 8
J 0
(-3412 3508);
DISPLAY 0.489362 (-3412 3508);
PAINT GREEN (-3412 3508);
FORCEPROP 2 LAST CDS_LIB mstr_standard
J 0
(-3350 3500);
DISPLAY 0.723404 (-3350 3500);
PAINT MONO (-3350 3500);
DISPLAY INVISIBLE (-3350 3500);
FORCEPROP 1 LAST BODY_TYPE PLUMBING
J 0
(-3350 3550);
DISPLAY 0.872340 (-3350 3550);
PAINT GREEN (-3350 3550);
DISPLAY INVISIBLE (-3350 3550);
FORCEPROP 1 LAST HDL_TAP TRUE
J 0
(-3025 3375);
DISPLAY 0.872340 (-3025 3375);
DISPLAY INVISIBLE (-3025 3375);
FORCEPROP 1 LAST PATH I227
J 0
(-3352 3500);
DISPLAY 0.872340 (-3352 3500);
PAINT GREEN (-3352 3500);
DISPLAY INVISIBLE (-3352 3500);
FORCEADD TAP..1
(-3350 3400);
FORCEPROP 3 LASTPIN (-3400 3400) SIG_NAME M_J_CPU1_SB_DQS_DP<7>
J 0
(-3390 3410);
DISPLAY 0.659574 (-3390 3410);
PAINT MONO (-3390 3410);
DISPLAY INVISIBLE (-3390 3410);
FORCEPROP 1 LASTPIN (-3400 3400) BN 7
J 0
(-3412 3408);
DISPLAY 0.489362 (-3412 3408);
PAINT GREEN (-3412 3408);
FORCEPROP 2 LAST CDS_LIB mstr_standard
J 0
(-3350 3400);
DISPLAY 0.723404 (-3350 3400);
PAINT MONO (-3350 3400);
DISPLAY INVISIBLE (-3350 3400);
FORCEPROP 1 LAST BODY_TYPE PLUMBING
J 0
(-3350 3450);
DISPLAY 0.872340 (-3350 3450);
PAINT GREEN (-3350 3450);
DISPLAY INVISIBLE (-3350 3450);
FORCEPROP 1 LAST HDL_TAP TRUE
J 0
(-3025 3275);
DISPLAY 0.872340 (-3025 3275);
DISPLAY INVISIBLE (-3025 3275);
FORCEPROP 1 LAST PATH I228
J 0
(-3352 3400);
DISPLAY 0.872340 (-3352 3400);
PAINT GREEN (-3352 3400);
DISPLAY INVISIBLE (-3352 3400);
FORCEADD TAP..1
(-3350 3300);
FORCEPROP 3 LASTPIN (-3400 3300) SIG_NAME M_J_CPU1_SB_DQS_DP<6>
J 0
(-3390 3310);
DISPLAY 0.659574 (-3390 3310);
PAINT MONO (-3390 3310);
DISPLAY INVISIBLE (-3390 3310);
FORCEPROP 1 LASTPIN (-3400 3300) BN 6
J 0
(-3412 3308);
DISPLAY 0.489362 (-3412 3308);
PAINT GREEN (-3412 3308);
FORCEPROP 2 LAST CDS_LIB mstr_standard
J 0
(-3350 3300);
DISPLAY 0.723404 (-3350 3300);
PAINT MONO (-3350 3300);
DISPLAY INVISIBLE (-3350 3300);
FORCEPROP 1 LAST BODY_TYPE PLUMBING
J 0
(-3350 3350);
DISPLAY 0.872340 (-3350 3350);
PAINT GREEN (-3350 3350);
DISPLAY INVISIBLE (-3350 3350);
FORCEPROP 1 LAST HDL_TAP TRUE
J 0
(-3025 3175);
DISPLAY 0.872340 (-3025 3175);
DISPLAY INVISIBLE (-3025 3175);
FORCEPROP 1 LAST PATH I229
J 0
(-3352 3300);
DISPLAY 0.872340 (-3352 3300);
PAINT GREEN (-3352 3300);
DISPLAY INVISIBLE (-3352 3300);
FORCEADD TAP..1
R 2
(-7550 3125);
FORCEPROP 3 LASTPIN (-7500 3125) SIG_NAME M_J_CPU1_SB_CB<0>
J 0
(-7490 3135);
DISPLAY 0.659574 (-7490 3135);
PAINT MONO (-7490 3135);
DISPLAY INVISIBLE (-7490 3135);
FORCEPROP 1 LASTPIN (-7500 3125) BN 0
J 2
(-7488 3133);
DISPLAY 0.489362 (-7488 3133);
PAINT GREEN (-7488 3133);
FORCEPROP 2 LAST CDS_LIB mstr_standard
J 0
(-7550 3125);
DISPLAY 0.723404 (-7550 3125);
PAINT MONO (-7550 3125);
DISPLAY INVISIBLE (-7550 3125);
FORCEPROP 1 LAST BODY_TYPE PLUMBING
J 2
(-7550 3175);
DISPLAY 0.872340 (-7550 3175);
PAINT GREEN (-7550 3175);
DISPLAY INVISIBLE (-7550 3175);
FORCEPROP 1 LAST HDL_TAP TRUE
J 2
(-7875 3000);
DISPLAY 0.872340 (-7875 3000);
DISPLAY INVISIBLE (-7875 3000);
FORCEPROP 1 LAST PATH I23
J 2
(-7548 3125);
DISPLAY 0.872340 (-7548 3125);
PAINT GREEN (-7548 3125);
DISPLAY INVISIBLE (-7548 3125);
FORCEADD TAP..1
(-3350 3200);
FORCEPROP 3 LASTPIN (-3400 3200) SIG_NAME M_J_CPU1_SB_DQS_DP<5>
J 0
(-3390 3210);
DISPLAY 0.659574 (-3390 3210);
PAINT MONO (-3390 3210);
DISPLAY INVISIBLE (-3390 3210);
FORCEPROP 1 LASTPIN (-3400 3200) BN 5
J 0
(-3412 3208);
DISPLAY 0.489362 (-3412 3208);
PAINT GREEN (-3412 3208);
FORCEPROP 2 LAST CDS_LIB mstr_standard
J 0
(-3350 3200);
DISPLAY 0.723404 (-3350 3200);
PAINT MONO (-3350 3200);
DISPLAY INVISIBLE (-3350 3200);
FORCEPROP 1 LAST BODY_TYPE PLUMBING
J 0
(-3350 3250);
DISPLAY 0.872340 (-3350 3250);
PAINT GREEN (-3350 3250);
DISPLAY INVISIBLE (-3350 3250);
FORCEPROP 1 LAST HDL_TAP TRUE
J 0
(-3025 3075);
DISPLAY 0.872340 (-3025 3075);
DISPLAY INVISIBLE (-3025 3075);
FORCEPROP 1 LAST PATH I230
J 0
(-3352 3200);
DISPLAY 0.872340 (-3352 3200);
PAINT GREEN (-3352 3200);
DISPLAY INVISIBLE (-3352 3200);
FORCEADD TAP..1
(-3350 3100);
FORCEPROP 3 LASTPIN (-3400 3100) SIG_NAME M_J_CPU1_SB_DQS_DP<4>
J 0
(-3390 3110);
DISPLAY 0.659574 (-3390 3110);
PAINT MONO (-3390 3110);
DISPLAY INVISIBLE (-3390 3110);
FORCEPROP 1 LASTPIN (-3400 3100) BN 4
J 0
(-3412 3108);
DISPLAY 0.489362 (-3412 3108);
PAINT GREEN (-3412 3108);
FORCEPROP 2 LAST CDS_LIB mstr_standard
J 0
(-3350 3100);
DISPLAY 0.723404 (-3350 3100);
PAINT MONO (-3350 3100);
DISPLAY INVISIBLE (-3350 3100);
FORCEPROP 1 LAST BODY_TYPE PLUMBING
J 0
(-3350 3150);
DISPLAY 0.872340 (-3350 3150);
PAINT GREEN (-3350 3150);
DISPLAY INVISIBLE (-3350 3150);
FORCEPROP 1 LAST HDL_TAP TRUE
J 0
(-3025 2975);
DISPLAY 0.872340 (-3025 2975);
DISPLAY INVISIBLE (-3025 2975);
FORCEPROP 1 LAST PATH I231
J 0
(-3352 3100);
DISPLAY 0.872340 (-3352 3100);
PAINT GREEN (-3352 3100);
DISPLAY INVISIBLE (-3352 3100);
FORCEADD TAP..1
(-3350 2900);
FORCEPROP 3 LASTPIN (-3400 2900) SIG_NAME M_J_CPU1_SB_DQS_DP<2>
J 0
(-3390 2910);
DISPLAY 0.659574 (-3390 2910);
PAINT MONO (-3390 2910);
DISPLAY INVISIBLE (-3390 2910);
FORCEPROP 1 LASTPIN (-3400 2900) BN 2
J 0
(-3412 2908);
DISPLAY 0.489362 (-3412 2908);
PAINT GREEN (-3412 2908);
FORCEPROP 2 LAST CDS_LIB mstr_standard
J 0
(-3350 2900);
DISPLAY 0.723404 (-3350 2900);
PAINT MONO (-3350 2900);
DISPLAY INVISIBLE (-3350 2900);
FORCEPROP 1 LAST BODY_TYPE PLUMBING
J 0
(-3350 2950);
DISPLAY 0.872340 (-3350 2950);
PAINT GREEN (-3350 2950);
DISPLAY INVISIBLE (-3350 2950);
FORCEPROP 1 LAST HDL_TAP TRUE
J 0
(-3025 2775);
DISPLAY 0.872340 (-3025 2775);
DISPLAY INVISIBLE (-3025 2775);
FORCEPROP 1 LAST PATH I232
J 0
(-3352 2900);
DISPLAY 0.872340 (-3352 2900);
PAINT GREEN (-3352 2900);
DISPLAY INVISIBLE (-3352 2900);
FORCEADD TAP..1
(-3350 3000);
FORCEPROP 3 LASTPIN (-3400 3000) SIG_NAME M_J_CPU1_SB_DQS_DP<3>
J 0
(-3390 3010);
DISPLAY 0.659574 (-3390 3010);
PAINT MONO (-3390 3010);
DISPLAY INVISIBLE (-3390 3010);
FORCEPROP 1 LASTPIN (-3400 3000) BN 3
J 0
(-3412 3008);
DISPLAY 0.489362 (-3412 3008);
PAINT GREEN (-3412 3008);
FORCEPROP 2 LAST CDS_LIB mstr_standard
J 0
(-3350 3000);
DISPLAY 0.723404 (-3350 3000);
PAINT MONO (-3350 3000);
DISPLAY INVISIBLE (-3350 3000);
FORCEPROP 1 LAST BODY_TYPE PLUMBING
J 0
(-3350 3050);
DISPLAY 0.872340 (-3350 3050);
PAINT GREEN (-3350 3050);
DISPLAY INVISIBLE (-3350 3050);
FORCEPROP 1 LAST HDL_TAP TRUE
J 0
(-3025 2875);
DISPLAY 0.872340 (-3025 2875);
DISPLAY INVISIBLE (-3025 2875);
FORCEPROP 1 LAST PATH I233
J 0
(-3352 3000);
DISPLAY 0.872340 (-3352 3000);
PAINT GREEN (-3352 3000);
DISPLAY INVISIBLE (-3352 3000);
FORCEADD TAP..1
(-3350 2800);
FORCEPROP 3 LASTPIN (-3400 2800) SIG_NAME M_J_CPU1_SB_DQS_DP<1>
J 0
(-3390 2810);
DISPLAY 0.659574 (-3390 2810);
PAINT MONO (-3390 2810);
DISPLAY INVISIBLE (-3390 2810);
FORCEPROP 1 LASTPIN (-3400 2800) BN 1
J 0
(-3412 2808);
DISPLAY 0.489362 (-3412 2808);
PAINT GREEN (-3412 2808);
FORCEPROP 2 LAST CDS_LIB mstr_standard
J 0
(-3350 2800);
DISPLAY 0.723404 (-3350 2800);
PAINT MONO (-3350 2800);
DISPLAY INVISIBLE (-3350 2800);
FORCEPROP 1 LAST BODY_TYPE PLUMBING
J 0
(-3350 2850);
DISPLAY 0.872340 (-3350 2850);
PAINT GREEN (-3350 2850);
DISPLAY INVISIBLE (-3350 2850);
FORCEPROP 1 LAST HDL_TAP TRUE
J 0
(-3025 2675);
DISPLAY 0.872340 (-3025 2675);
DISPLAY INVISIBLE (-3025 2675);
FORCEPROP 1 LAST PATH I234
J 0
(-3352 2800);
DISPLAY 0.872340 (-3352 2800);
PAINT GREEN (-3352 2800);
DISPLAY INVISIBLE (-3352 2800);
FORCEADD TAP..1
(-3350 2700);
FORCEPROP 3 LASTPIN (-3400 2700) SIG_NAME M_J_CPU1_SB_DQS_DP<0>
J 0
(-3390 2710);
DISPLAY 0.659574 (-3390 2710);
PAINT MONO (-3390 2710);
DISPLAY INVISIBLE (-3390 2710);
FORCEPROP 1 LASTPIN (-3400 2700) BN 0
J 0
(-3412 2708);
DISPLAY 0.489362 (-3412 2708);
PAINT GREEN (-3412 2708);
FORCEPROP 2 LAST CDS_LIB mstr_standard
J 0
(-3350 2700);
DISPLAY 0.723404 (-3350 2700);
PAINT MONO (-3350 2700);
DISPLAY INVISIBLE (-3350 2700);
FORCEPROP 1 LAST BODY_TYPE PLUMBING
J 0
(-3350 2750);
DISPLAY 0.872340 (-3350 2750);
PAINT GREEN (-3350 2750);
DISPLAY INVISIBLE (-3350 2750);
FORCEPROP 1 LAST HDL_TAP TRUE
J 0
(-3025 2575);
DISPLAY 0.872340 (-3025 2575);
DISPLAY INVISIBLE (-3025 2575);
FORCEPROP 1 LAST PATH I235
J 0
(-3352 2700);
DISPLAY 0.872340 (-3352 2700);
PAINT GREEN (-3352 2700);
DISPLAY INVISIBLE (-3352 2700);
FORCEADD SCONN288_DDR506112002KQ..2
(-4300 3650);
FORCEPROP 1 LAST LOCATION J29
J 0
(-4900 4975);
DISPLAY 0.468085 (-4900 4975);
PAINT SKYBLUE (-4900 4975);
FORCEPROP 0 LAST $SEC 2
J 0
(-4750 5125);
DISPLAY 0.680851 (-4750 5125);
PAINT MONO (-4750 5125);
DISPLAY INVISIBLE (-4750 5125);
FORCEPROP 0 LAST CDS_SEC 2
J 0
(-4750 5125);
DISPLAY 1.021277 (-4750 5125);
DISPLAY INVISIBLE (-4750 5125);
FORCEPROP 0 LASTPIN (-3550 3700) $PN 12
J 0
(-3540 3710);
DISPLAY 0.680851 (-3540 3710);
PAINT MONO (-3540 3710);
FORCEPROP 0 LASTPIN (-3550 3750) $PN 11
J 0
(-3540 3760);
DISPLAY 0.680851 (-3540 3760);
PAINT MONO (-3540 3760);
FORCEPROP 0 LASTPIN (-3550 2650) $PN 105
J 0
(-3540 2660);
DISPLAY 0.680851 (-3540 2660);
PAINT MONO (-3540 2660);
FORCEPROP 0 LASTPIN (-3550 2700) $PN 104
J 0
(-3540 2710);
DISPLAY 0.680851 (-3540 2710);
PAINT MONO (-3540 2710);
FORCEPROP 0 LASTPIN (-3550 3800) $PN 23
J 0
(-3540 3810);
DISPLAY 0.680851 (-3540 3810);
PAINT MONO (-3540 3810);
FORCEPROP 0 LASTPIN (-3550 3850) $PN 22
J 0
(-3540 3860);
DISPLAY 0.680851 (-3540 3860);
PAINT MONO (-3540 3860);
FORCEPROP 0 LASTPIN (-3550 2750) $PN 116
J 0
(-3540 2760);
DISPLAY 0.680851 (-3540 2760);
PAINT MONO (-3540 2760);
FORCEPROP 0 LASTPIN (-3550 2800) $PN 115
J 0
(-3540 2810);
DISPLAY 0.680851 (-3540 2810);
PAINT MONO (-3540 2810);
FORCEPROP 0 LASTPIN (-3550 3900) $PN 34
J 0
(-3540 3910);
DISPLAY 0.680851 (-3540 3910);
PAINT MONO (-3540 3910);
FORCEPROP 0 LASTPIN (-3550 3950) $PN 33
J 0
(-3540 3960);
DISPLAY 0.680851 (-3540 3960);
PAINT MONO (-3540 3960);
FORCEPROP 0 LASTPIN (-3550 2850) $PN 127
J 0
(-3540 2860);
DISPLAY 0.680851 (-3540 2860);
PAINT MONO (-3540 2860);
FORCEPROP 0 LASTPIN (-3550 2900) $PN 126
J 0
(-3540 2910);
DISPLAY 0.680851 (-3540 2910);
PAINT MONO (-3540 2910);
FORCEPROP 0 LASTPIN (-3550 4000) $PN 45
J 0
(-3540 4010);
DISPLAY 0.680851 (-3540 4010);
PAINT MONO (-3540 4010);
FORCEPROP 0 LASTPIN (-3550 4050) $PN 44
J 0
(-3540 4060);
DISPLAY 0.680851 (-3540 4060);
PAINT MONO (-3540 4060);
FORCEPROP 0 LASTPIN (-3550 2950) $PN 138
J 0
(-3540 2960);
DISPLAY 0.680851 (-3540 2960);
PAINT MONO (-3540 2960);
FORCEPROP 0 LASTPIN (-3550 3000) $PN 137
J 0
(-3540 3010);
DISPLAY 0.680851 (-3540 3010);
PAINT MONO (-3540 3010);
FORCEPROP 0 LASTPIN (-3550 4100) $PN 56
J 0
(-3540 4110);
DISPLAY 0.680851 (-3540 4110);
PAINT MONO (-3540 4110);
FORCEPROP 0 LASTPIN (-3550 4150) $PN 55
J 0
(-3540 4160);
DISPLAY 0.680851 (-3540 4160);
PAINT MONO (-3540 4160);
FORCEPROP 0 LASTPIN (-3550 3050) $PN 238
J 0
(-3540 3060);
DISPLAY 0.680851 (-3540 3060);
PAINT MONO (-3540 3060);
FORCEPROP 0 LASTPIN (-3550 3100) $PN 239
J 0
(-3540 3110);
DISPLAY 0.680851 (-3540 3110);
PAINT MONO (-3540 3110);
FORCEPROP 0 LASTPIN (-3550 4200) $PN 156
J 0
(-3540 4210);
DISPLAY 0.680851 (-3540 4210);
PAINT MONO (-3540 4210);
FORCEPROP 0 LASTPIN (-3550 4250) $PN 157
J 0
(-3540 4260);
DISPLAY 0.680851 (-3540 4260);
PAINT MONO (-3540 4260);
FORCEPROP 0 LASTPIN (-3550 3150) $PN 249
J 0
(-3540 3160);
DISPLAY 0.680851 (-3540 3160);
PAINT MONO (-3540 3160);
FORCEPROP 0 LASTPIN (-3550 3200) $PN 250
J 0
(-3540 3210);
DISPLAY 0.680851 (-3540 3210);
PAINT MONO (-3540 3210);
FORCEPROP 0 LASTPIN (-3550 4300) $PN 167
J 0
(-3540 4310);
DISPLAY 0.680851 (-3540 4310);
PAINT MONO (-3540 4310);
FORCEPROP 0 LASTPIN (-3550 4350) $PN 168
J 0
(-3540 4360);
DISPLAY 0.680851 (-3540 4360);
PAINT MONO (-3540 4360);
FORCEPROP 0 LASTPIN (-3550 3250) $PN 260
J 0
(-3540 3260);
DISPLAY 0.680851 (-3540 3260);
PAINT MONO (-3540 3260);
FORCEPROP 0 LASTPIN (-3550 3300) $PN 261
J 0
(-3540 3310);
DISPLAY 0.680851 (-3540 3310);
PAINT MONO (-3540 3310);
FORCEPROP 0 LASTPIN (-3550 4400) $PN 178
J 0
(-3540 4410);
DISPLAY 0.680851 (-3540 4410);
PAINT MONO (-3540 4410);
FORCEPROP 0 LASTPIN (-3550 4450) $PN 179
J 0
(-3540 4460);
DISPLAY 0.680851 (-3540 4460);
PAINT MONO (-3540 4460);
FORCEPROP 0 LASTPIN (-3550 3350) $PN 271
J 0
(-3540 3360);
DISPLAY 0.680851 (-3540 3360);
PAINT MONO (-3540 3360);
FORCEPROP 0 LASTPIN (-3550 3400) $PN 272
J 0
(-3540 3410);
DISPLAY 0.680851 (-3540 3410);
PAINT MONO (-3540 3410);
FORCEPROP 0 LASTPIN (-3550 4500) $PN 189
J 0
(-3540 4510);
DISPLAY 0.680851 (-3540 4510);
PAINT MONO (-3540 4510);
FORCEPROP 0 LASTPIN (-3550 4550) $PN 190
J 0
(-3540 4560);
DISPLAY 0.680851 (-3540 4560);
PAINT MONO (-3540 4560);
FORCEPROP 0 LASTPIN (-3550 3450) $PN 282
J 0
(-3540 3460);
DISPLAY 0.680851 (-3540 3460);
PAINT MONO (-3540 3460);
FORCEPROP 0 LASTPIN (-3550 3500) $PN 283
J 0
(-3540 3510);
DISPLAY 0.680851 (-3540 3510);
PAINT MONO (-3540 3510);
FORCEPROP 0 LASTPIN (-3550 4600) $PN 200
J 0
(-3540 4610);
DISPLAY 0.680851 (-3540 4610);
PAINT MONO (-3540 4610);
FORCEPROP 0 LASTPIN (-3550 4650) $PN 201
J 0
(-3540 4660);
DISPLAY 0.680851 (-3540 4660);
PAINT MONO (-3540 4660);
FORCEPROP 0 LASTPIN (-3550 3550) $PN 94
J 0
(-3540 3560);
DISPLAY 0.680851 (-3540 3560);
PAINT MONO (-3540 3560);
FORCEPROP 0 LASTPIN (-3550 3600) $PN 93
J 0
(-3540 3610);
DISPLAY 0.680851 (-3540 3610);
PAINT MONO (-3540 3610);
FORCEPROP 1 LAST MATERIAL IO
J 0
(-4900 4825);
DISPLAY 0.468085 (-4900 4825);
PAINT SKYBLUE (-4900 4825);
FORCEPROP 2 LAST PART_TYPE SMLF
J 0
(-4750 5075);
DISPLAY 1.021277 (-4750 5075);
FORCEPROP 2 LAST VALUE SCONN288_DDR506112002KQ
J 0
(-4750 5025);
DISPLAY 0.489362 (-4750 5025);
PAINT SKYBLUE (-4750 5025);
FORCEPROP 2 LAST CDS_LIB pure_quanta
J 0
(-4300 3650);
DISPLAY INVISIBLE (-4300 3650);
FORCEPROP 1 LAST NEEDS_NO_SIZE TRUE
J 0
(-4300 3650);
DISPLAY 0.723404 (-4300 3650);
PAINT GREEN (-4300 3650);
DISPLAY INVISIBLE (-4300 3650);
FORCEPROP 1 LAST CDS_LMAN_SYM_OUTLINE -600,1150,600,-1150
J 0
(-4300 3650);
DISPLAY 0.468085 (-4300 3650);
PAINT GREEN (-4300 3650);
DISPLAY INVISIBLE (-4300 3650);
FORCEPROP 1 LAST PATH I236
J 0
(-4300 3650);
DISPLAY 0.723404 (-4300 3650);
PAINT GREEN (-4300 3650);
DISPLAY INVISIBLE (-4300 3650);
FORCEPROP 1 LAST PART_NUMBER DFHST8FS479
J 0
(-4900 4900);
DISPLAY 0.468085 (-4900 4900);
PAINT SKYBLUE (-4900 4900);
DISPLAY INVISIBLE (-4900 4900);
FORCEADD GND..1
(-2725 5425);
FORCEPROP 3 LASTPIN (-2725 5475) SIG_NAME GND\g
J 0
(-2715 5485);
DISPLAY 0.659574 (-2715 5485);
PAINT MONO (-2715 5485);
DISPLAY INVISIBLE (-2715 5485);
FORCEPROP 2 LAST ROOM MEM_EFGH_DECOUPLING_CAPS
J 0
(-2700 5500);
DISPLAY 0.659574 (-2700 5500);
PAINT RED (-2700 5500);
DISPLAY INVISIBLE (-2700 5500);
FORCEPROP 1 LAST SIZE 1B
J 0
(-2650 5375);
DISPLAY 0.723404 (-2650 5375);
PAINT GREEN (-2650 5375);
DISPLAY INVISIBLE (-2650 5375);
FORCEPROP 2 LAST BOM_COST MEM
J 0
(-2700 5550);
DISPLAY 0.659574 (-2700 5550);
DISPLAY INVISIBLE (-2700 5550);
FORCEPROP 2 LAST CDS_LIB pure_quanta_power
J 0
(-2725 5425);
DISPLAY INVISIBLE (-2725 5425);
FORCEPROP 1 LAST HDL_POWER GND
J 0
(-2725 5575);
DISPLAY 0.723404 (-2725 5575);
PAINT GREEN (-2725 5575);
DISPLAY INVISIBLE (-2725 5575);
FORCEPROP 1 LAST PATH I237
J 0
(-2650 5425);
DISPLAY 0.872340 (-2650 5425);
PAINT AQUA (-2650 5425);
DISPLAY INVISIBLE (-2650 5425);
FORCEADD Q_CAP..1
R 2
(-2725 5775);
FORCEPROP 1 LAST LOCATION C536
J 2
(-2775 5875);
DISPLAY 0.489362 (-2775 5875);
PAINT SKYBLUE (-2775 5875);
FORCEPROP 0 LAST $SEC 1
J 0
(-2775 5925);
DISPLAY 0.680851 (-2775 5925);
PAINT MONO (-2775 5925);
DISPLAY INVISIBLE (-2775 5925);
FORCEPROP 0 LAST CDS_SEC 1
J 0
(-2775 5925);
DISPLAY 0.680851 (-2775 5925);
DISPLAY INVISIBLE (-2775 5925);
FORCEPROP 1 LASTPIN (-2725 5875) $PN 1
J 2
(-2735 5855);
DISPLAY 0.489362 (-2735 5855);
PAINT MONO (-2735 5855);
FORCEPROP 1 LASTPIN (-2725 5675) $PN 2
J 2
(-2735 5655);
DISPLAY 0.489362 (-2735 5655);
PAINT MONO (-2735 5655);
FORCEPROP 1 LAST MATERIAL X6S
J 2
(-2775 5675);
DISPLAY 0.489362 (-2775 5675);
PAINT SKYBLUE (-2775 5675);
FORCEPROP 1 LAST TOLERANCE 10%
J 2
(-2775 5725);
DISPLAY 0.489362 (-2775 5725);
PAINT SKYBLUE (-2775 5725);
FORCEPROP 1 LAST VALUE 10UF
J 2
(-2775 5825);
DISPLAY 0.489362 (-2775 5825);
PAINT SKYBLUE (-2775 5825);
FORCEPROP 1 LAST VOLTAGE 25V
J 2
(-2775 5775);
DISPLAY 0.489362 (-2775 5775);
PAINT SKYBLUE (-2775 5775);
FORCEPROP 1 LAST PACK_TYPE C0805
J 2
(-2775 5575);
DISPLAY 0.489362 (-2775 5575);
PAINT SKYBLUE (-2775 5575);
FORCEPROP 0 LAST BOM_COST MEM
J 2
(-2780 5920);
DISPLAY 0.595745 (-2780 5920);
PAINT MONO (-2780 5920);
DISPLAY INVISIBLE (-2780 5920);
FORCEPROP 2 LAST CDS_LIB pure_quanta
J 0
(-2725 5775);
DISPLAY INVISIBLE (-2725 5775);
FORCEPROP 2 LAST ROOM 
J 2
(-2780 5920);
DISPLAY 0.595745 (-2780 5920);
PAINT RED (-2780 5920);
DISPLAY INVISIBLE (-2780 5920);
FORCEPROP 1 LAST PATH I238
J 2
(-2775 5925);
DISPLAY 0.978723 (-2775 5925);
PAINT WHITE (-2775 5925);
DISPLAY INVISIBLE (-2775 5925);
FORCEPROP 1 LAST PART_NUMBER CH6104KEA00
J 2
(-2775 5625);
DISPLAY 0.489362 (-2775 5625);
PAINT SKYBLUE (-2775 5625);
DISPLAY INVISIBLE (-2775 5625);
FORCEADD Q_CAP..1
R 2
(-2150 5775);
FORCEPROP 1 LAST LOCATION C537
J 2
(-2200 5875);
DISPLAY 0.489362 (-2200 5875);
PAINT SKYBLUE (-2200 5875);
FORCEPROP 0 LAST $SEC 1
J 0
(-2200 5925);
DISPLAY 0.680851 (-2200 5925);
PAINT MONO (-2200 5925);
DISPLAY INVISIBLE (-2200 5925);
FORCEPROP 0 LAST CDS_SEC 1
J 0
(-2200 5925);
DISPLAY 0.680851 (-2200 5925);
DISPLAY INVISIBLE (-2200 5925);
FORCEPROP 1 LASTPIN (-2150 5875) $PN 1
J 2
(-2160 5855);
DISPLAY 0.489362 (-2160 5855);
PAINT MONO (-2160 5855);
FORCEPROP 1 LASTPIN (-2150 5675) $PN 2
J 2
(-2160 5655);
DISPLAY 0.489362 (-2160 5655);
PAINT MONO (-2160 5655);
FORCEPROP 1 LAST MATERIAL X6S
J 2
(-2200 5675);
DISPLAY 0.489362 (-2200 5675);
PAINT SKYBLUE (-2200 5675);
FORCEPROP 1 LAST TOLERANCE 10%
J 2
(-2200 5725);
DISPLAY 0.489362 (-2200 5725);
PAINT SKYBLUE (-2200 5725);
FORCEPROP 1 LAST VALUE 10UF
J 2
(-2200 5825);
DISPLAY 0.489362 (-2200 5825);
PAINT SKYBLUE (-2200 5825);
FORCEPROP 1 LAST VOLTAGE 25V
J 2
(-2200 5775);
DISPLAY 0.489362 (-2200 5775);
PAINT SKYBLUE (-2200 5775);
FORCEPROP 1 LAST PACK_TYPE C0805
J 2
(-2200 5575);
DISPLAY 0.489362 (-2200 5575);
PAINT SKYBLUE (-2200 5575);
FORCEPROP 0 LAST BOM_COST MEM
J 2
(-2205 5920);
DISPLAY 0.595745 (-2205 5920);
PAINT MONO (-2205 5920);
DISPLAY INVISIBLE (-2205 5920);
FORCEPROP 2 LAST CDS_LIB pure_quanta
J 0
(-2150 5775);
DISPLAY INVISIBLE (-2150 5775);
FORCEPROP 2 LAST ROOM 
J 2
(-2205 5920);
DISPLAY 0.595745 (-2205 5920);
PAINT RED (-2205 5920);
DISPLAY INVISIBLE (-2205 5920);
FORCEPROP 1 LAST PATH I239
J 2
(-2200 5925);
DISPLAY 0.978723 (-2200 5925);
PAINT WHITE (-2200 5925);
DISPLAY INVISIBLE (-2200 5925);
FORCEPROP 1 LAST PART_NUMBER CH6104KEA00
J 2
(-2200 5625);
DISPLAY 0.489362 (-2200 5625);
PAINT SKYBLUE (-2200 5625);
DISPLAY INVISIBLE (-2200 5625);
FORCEADD TAP..1
R 2
(-7550 3175);
FORCEPROP 3 LASTPIN (-7500 3175) SIG_NAME M_J_CPU1_SB_CB<1>
J 0
(-7490 3185);
DISPLAY 0.659574 (-7490 3185);
PAINT MONO (-7490 3185);
DISPLAY INVISIBLE (-7490 3185);
FORCEPROP 1 LASTPIN (-7500 3175) BN 1
J 2
(-7488 3183);
DISPLAY 0.489362 (-7488 3183);
PAINT GREEN (-7488 3183);
FORCEPROP 2 LAST CDS_LIB mstr_standard
J 0
(-7550 3175);
DISPLAY 0.723404 (-7550 3175);
PAINT MONO (-7550 3175);
DISPLAY INVISIBLE (-7550 3175);
FORCEPROP 1 LAST BODY_TYPE PLUMBING
J 2
(-7550 3225);
DISPLAY 0.872340 (-7550 3225);
PAINT GREEN (-7550 3225);
DISPLAY INVISIBLE (-7550 3225);
FORCEPROP 1 LAST HDL_TAP TRUE
J 2
(-7875 3050);
DISPLAY 0.872340 (-7875 3050);
DISPLAY INVISIBLE (-7875 3050);
FORCEPROP 1 LAST PATH I24
J 2
(-7548 3175);
DISPLAY 0.872340 (-7548 3175);
PAINT GREEN (-7548 3175);
DISPLAY INVISIBLE (-7548 3175);
FORCEADD UNIVERSAL_POWER..1
(-2725 6100);
FORCEPROP 3 LASTPIN (-2725 6050) SIG_NAME P12V_MEM_CPU1\g
J 0
(-2715 6060);
DISPLAY 0.659574 (-2715 6060);
PAINT MONO (-2715 6060);
DISPLAY INVISIBLE (-2715 6060);
FORCEPROP 1 LAST HDL_POWER P12V_MEM_CPU1
J 1
(-2725 6150);
DISPLAY 0.489362 (-2725 6150);
PAINT GREEN (-2725 6150);
FORCEPROP 2 LAST CDS_LIB pure_quanta_power
J 0
(-2725 6100);
DISPLAY INVISIBLE (-2725 6100);
FORCEPROP 1 LAST PATH I240
J 0
(-2675 6125);
DISPLAY 0.872340 (-2675 6125);
PAINT AQUA (-2675 6125);
DISPLAY INVISIBLE (-2675 6125);
FORCEADD OFFPAGE..1
(-8175 2575);
FORCEPROP 2 LAST $XR5 109 
J 0
(-9027 2575);
DISPLAY 0.638298 (-9027 2575);
PAINT MONO (-9027 2575);
FORCEPROP 2 LAST $XR4 108 
J 0
(-8907 2575);
DISPLAY 0.638298 (-8907 2575);
PAINT MONO (-8907 2575);
FORCEPROP 2 LAST $XR3 106 
J 0
(-8787 2575);
DISPLAY 0.638298 (-8787 2575);
PAINT MONO (-8787 2575);
FORCEPROP 2 LAST $XR2 105 
J 0
(-8667 2575);
DISPLAY 0.638298 (-8667 2575);
PAINT MONO (-8667 2575);
FORCEPROP 2 LAST $XR1 104 
J 0
(-8547 2575);
DISPLAY 0.638298 (-8547 2575);
PAINT MONO (-8547 2575);
FORCEPROP 2 LAST $XR0 159 
J 0
(-8427 2575);
DISPLAY 0.638298 (-8427 2575);
PAINT MONO (-8427 2575);
FORCEPROP 2 LAST CDS_LIB mstr_standard
J 0
(-8175 2575);
DISPLAY 0.808511 (-8175 2575);
DISPLAY INVISIBLE (-8175 2575);
FORCEPROP 1 LAST OFFPAGE TRUE
J 0
(-7850 2450);
DISPLAY 0.872340 (-7850 2450);
PAINT GREEN (-7850 2450);
DISPLAY INVISIBLE (-7850 2450);
FORCEPROP 1 LAST COMMENT_BODY TRUE
J 0
(-8050 2475);
DISPLAY 0.872340 (-8050 2475);
PAINT GREEN (-8050 2475);
DISPLAY INVISIBLE (-8050 2475);
FORCEPROP 2 LAST PATH I241
J 0
(-8450 2625);
DISPLAY 0.680851 (-8450 2625);
DISPLAY INVISIBLE (-8450 2625);
FORCEADD Q_RES..1
(-7600 2575);
FORCEPROP 1 LAST LOCATION R1589
J 0
(-7650 2600);
DISPLAY 0.510638 (-7650 2600);
PAINT SKYBLUE (-7650 2600);
FORCEPROP 0 LAST $SEC 1
J 0
(-7650 2675);
DISPLAY 0.680851 (-7650 2675);
PAINT MONO (-7650 2675);
DISPLAY INVISIBLE (-7650 2675);
FORCEPROP 0 LAST CDS_SEC 1
J 0
(-7650 2675);
DISPLAY 0.680851 (-7650 2675);
DISPLAY INVISIBLE (-7650 2675);
FORCEPROP 1 LASTPIN (-7700 2575) $PN 1
J 0
(-7688 2587);
DISPLAY 0.787234 (-7688 2587);
PAINT MONO (-7688 2587);
FORCEPROP 1 LASTPIN (-7500 2575) $PN 2
J 0
(-7538 2587);
DISPLAY 0.787234 (-7538 2587);
PAINT MONO (-7538 2587);
FORCEPROP 1 LAST VALUE 49.9
J 2
(-7450 2625);
DISPLAY 0.510638 (-7450 2625);
PAINT SKYBLUE (-7450 2625);
FORCEPROP 1 LAST TOLERANCE 1%
J 0
(-7600 2475);
DISPLAY 0.978723 (-7600 2475);
DISPLAY INVISIBLE (-7600 2475);
FORCEPROP 1 LAST WATTAGE 1/16W
J 2
(-7625 2425);
DISPLAY 0.978723 (-7625 2425);
DISPLAY INVISIBLE (-7625 2425);
FORCEPROP 1 LAST PACK_TYPE 0402LF
J 0
(-7350 2425);
DISPLAY 0.978723 (-7350 2425);
DISPLAY INVISIBLE (-7350 2425);
FORCEPROP 1 LAST MATERIAL CHIP
J 0
(-7600 2425);
DISPLAY 0.978723 (-7600 2425);
DISPLAY INVISIBLE (-7600 2425);
FORCEPROP 2 LAST CDS_LIB pure_quanta
J 0
(-7600 2575);
DISPLAY INVISIBLE (-7600 2575);
FORCEPROP 1 LAST PATH I242
J 0
(-7650 2725);
DISPLAY 0.978723 (-7650 2725);
PAINT WHITE (-7650 2725);
DISPLAY INVISIBLE (-7650 2725);
FORCEPROP 1 LAST PART_NUMBER CS04992FB07
J 0
(-7650 2675);
DISPLAY 0.978723 (-7650 2675);
DISPLAY INVISIBLE (-7650 2675);
FORCEADD Q_RES..1
(-8000 2775);
FORCEPROP 1 LAST LOCATION R1709
J 0
(-8200 2775);
DISPLAY 0.510638 (-8200 2775);
FORCEPROP 0 LAST $SEC 1
J 0
(-8175 2825);
DISPLAY 0.680851 (-8175 2825);
PAINT MONO (-8175 2825);
DISPLAY INVISIBLE (-8175 2825);
FORCEPROP 0 LAST CDS_SEC 1
J 0
(-8175 2825);
DISPLAY 0.680851 (-8175 2825);
DISPLAY INVISIBLE (-8175 2825);
FORCEPROP 1 LASTPIN (-8100 2775) $PN 1
J 0
(-8088 2787);
DISPLAY 0.787234 (-8088 2787);
PAINT MONO (-8088 2787);
FORCEPROP 1 LASTPIN (-7900 2775) $PN 2
J 0
(-7938 2787);
DISPLAY 0.787234 (-7938 2787);
PAINT MONO (-7938 2787);
FORCEPROP 1 LAST PACK_TYPE 0402LF
J 0
(-7950 2750);
DISPLAY 0.404255 (-7950 2750);
FORCEPROP 1 LAST MATERIAL CHIP
J 0
(-8100 2750);
DISPLAY 0.404255 (-8100 2750);
FORCEPROP 1 LAST VALUE 10
J 2
(-7850 2775);
DISPLAY 0.404255 (-7850 2775);
FORCEPROP 2 LAST CDS_LIB pure_quanta
J 0
(-8000 2775);
DISPLAY INVISIBLE (-8000 2775);
FORCEPROP 1 LAST WATTAGE 1/16W
J 2
(-8025 2625);
DISPLAY 0.978723 (-8025 2625);
DISPLAY INVISIBLE (-8025 2625);
FORCEPROP 1 LAST TOLERANCE 1%
J 0
(-8000 2675);
DISPLAY 0.978723 (-8000 2675);
DISPLAY INVISIBLE (-8000 2675);
FORCEPROP 1 LAST PATH I243
J 0
(-8050 2925);
DISPLAY 0.978723 (-8050 2925);
PAINT WHITE (-8050 2925);
DISPLAY INVISIBLE (-8050 2925);
FORCEPROP 1 LAST PART_NUMBER CS01002FB07
J 0
(-8050 2875);
DISPLAY 0.978723 (-8050 2875);
DISPLAY INVISIBLE (-8050 2875);
FORCEADD OFFPAGE..6
(-8675 2675);
FORCEPROP 2 LAST $XR5 159 
J 0
(-9075 2639);
DISPLAY 0.638298 (-9075 2639);
PAINT MONO (-9075 2639);
FORCEPROP 2 LAST $XR4 109 
J 0
(-8955 2639);
DISPLAY 0.638298 (-8955 2639);
PAINT MONO (-8955 2639);
FORCEPROP 2 LAST $XR3 108 
J 0
(-9315 2675);
DISPLAY 0.638298 (-9315 2675);
PAINT MONO (-9315 2675);
FORCEPROP 2 LAST $XR2 106 
J 0
(-9195 2675);
DISPLAY 0.638298 (-9195 2675);
PAINT MONO (-9195 2675);
FORCEPROP 2 LAST $XR1 105 
J 0
(-9075 2675);
DISPLAY 0.638298 (-9075 2675);
PAINT MONO (-9075 2675);
FORCEPROP 2 LAST $XR0 104 
J 0
(-8955 2675);
DISPLAY 0.638298 (-8955 2675);
PAINT MONO (-8955 2675);
FORCEPROP 2 LAST CDS_LIB mstr_standard
J 0
(-8675 2675);
DISPLAY 0.808511 (-8675 2675);
DISPLAY INVISIBLE (-8675 2675);
FORCEPROP 1 LAST OFFPAGE TRUE
J 0
(-8350 2550);
DISPLAY 0.872340 (-8350 2550);
PAINT GREEN (-8350 2550);
DISPLAY INVISIBLE (-8350 2550);
FORCEPROP 1 LAST COMMENT_BODY TRUE
J 0
(-8575 2600);
DISPLAY 0.872340 (-8575 2600);
PAINT GREEN (-8575 2600);
DISPLAY INVISIBLE (-8575 2600);
FORCEPROP 2 LAST PATH I244
J 0
(-8975 2725);
DISPLAY 0.680851 (-8975 2725);
DISPLAY INVISIBLE (-8975 2725);
FORCEADD TAP..1
R 2
(-7550 3225);
FORCEPROP 3 LASTPIN (-7500 3225) SIG_NAME M_J_CPU1_SB_CB<2>
J 0
(-7490 3235);
DISPLAY 0.659574 (-7490 3235);
PAINT MONO (-7490 3235);
DISPLAY INVISIBLE (-7490 3235);
FORCEPROP 1 LASTPIN (-7500 3225) BN 2
J 2
(-7488 3233);
DISPLAY 0.489362 (-7488 3233);
PAINT GREEN (-7488 3233);
FORCEPROP 2 LAST CDS_LIB mstr_standard
J 0
(-7550 3225);
DISPLAY 0.723404 (-7550 3225);
PAINT MONO (-7550 3225);
DISPLAY INVISIBLE (-7550 3225);
FORCEPROP 1 LAST BODY_TYPE PLUMBING
J 2
(-7550 3275);
DISPLAY 0.872340 (-7550 3275);
PAINT GREEN (-7550 3275);
DISPLAY INVISIBLE (-7550 3275);
FORCEPROP 1 LAST HDL_TAP TRUE
J 2
(-7875 3100);
DISPLAY 0.872340 (-7875 3100);
DISPLAY INVISIBLE (-7875 3100);
FORCEPROP 1 LAST PATH I25
J 2
(-7548 3225);
DISPLAY 0.872340 (-7548 3225);
PAINT GREEN (-7548 3225);
DISPLAY INVISIBLE (-7548 3225);
FORCEADD TAP..1
R 2
(-7550 3325);
FORCEPROP 3 LASTPIN (-7500 3325) SIG_NAME M_J_CPU1_SB_CB<4>
J 0
(-7490 3335);
DISPLAY 0.659574 (-7490 3335);
PAINT MONO (-7490 3335);
DISPLAY INVISIBLE (-7490 3335);
FORCEPROP 1 LASTPIN (-7500 3325) BN 4
J 2
(-7488 3333);
DISPLAY 0.489362 (-7488 3333);
PAINT GREEN (-7488 3333);
FORCEPROP 2 LAST CDS_LIB mstr_standard
J 0
(-7550 3325);
DISPLAY 0.723404 (-7550 3325);
PAINT MONO (-7550 3325);
DISPLAY INVISIBLE (-7550 3325);
FORCEPROP 1 LAST BODY_TYPE PLUMBING
J 2
(-7550 3375);
DISPLAY 0.872340 (-7550 3375);
PAINT GREEN (-7550 3375);
DISPLAY INVISIBLE (-7550 3375);
FORCEPROP 1 LAST HDL_TAP TRUE
J 2
(-7875 3200);
DISPLAY 0.872340 (-7875 3200);
DISPLAY INVISIBLE (-7875 3200);
FORCEPROP 1 LAST PATH I26
J 2
(-7548 3325);
DISPLAY 0.872340 (-7548 3325);
PAINT GREEN (-7548 3325);
DISPLAY INVISIBLE (-7548 3325);
FORCEADD TAP..1
R 2
(-7550 3275);
FORCEPROP 3 LASTPIN (-7500 3275) SIG_NAME M_J_CPU1_SB_CB<3>
J 0
(-7490 3285);
DISPLAY 0.659574 (-7490 3285);
PAINT MONO (-7490 3285);
DISPLAY INVISIBLE (-7490 3285);
FORCEPROP 1 LASTPIN (-7500 3275) BN 3
J 2
(-7488 3283);
DISPLAY 0.489362 (-7488 3283);
PAINT GREEN (-7488 3283);
FORCEPROP 2 LAST CDS_LIB mstr_standard
J 0
(-7550 3275);
DISPLAY 0.723404 (-7550 3275);
PAINT MONO (-7550 3275);
DISPLAY INVISIBLE (-7550 3275);
FORCEPROP 1 LAST BODY_TYPE PLUMBING
J 2
(-7550 3325);
DISPLAY 0.872340 (-7550 3325);
PAINT GREEN (-7550 3325);
DISPLAY INVISIBLE (-7550 3325);
FORCEPROP 1 LAST HDL_TAP TRUE
J 2
(-7875 3150);
DISPLAY 0.872340 (-7875 3150);
DISPLAY INVISIBLE (-7875 3150);
FORCEPROP 1 LAST PATH I27
J 2
(-7548 3275);
DISPLAY 0.872340 (-7548 3275);
PAINT GREEN (-7548 3275);
DISPLAY INVISIBLE (-7548 3275);
FORCEADD TAP..1
R 2
(-7550 3375);
FORCEPROP 3 LASTPIN (-7500 3375) SIG_NAME M_J_CPU1_SB_CB<5>
J 0
(-7490 3385);
DISPLAY 0.659574 (-7490 3385);
PAINT MONO (-7490 3385);
DISPLAY INVISIBLE (-7490 3385);
FORCEPROP 1 LASTPIN (-7500 3375) BN 5
J 2
(-7488 3383);
DISPLAY 0.489362 (-7488 3383);
PAINT GREEN (-7488 3383);
FORCEPROP 2 LAST CDS_LIB mstr_standard
J 0
(-7550 3375);
DISPLAY 0.723404 (-7550 3375);
PAINT MONO (-7550 3375);
DISPLAY INVISIBLE (-7550 3375);
FORCEPROP 1 LAST BODY_TYPE PLUMBING
J 2
(-7550 3425);
DISPLAY 0.872340 (-7550 3425);
PAINT GREEN (-7550 3425);
DISPLAY INVISIBLE (-7550 3425);
FORCEPROP 1 LAST HDL_TAP TRUE
J 2
(-7875 3250);
DISPLAY 0.872340 (-7875 3250);
DISPLAY INVISIBLE (-7875 3250);
FORCEPROP 1 LAST PATH I28
J 2
(-7548 3375);
DISPLAY 0.872340 (-7548 3375);
PAINT GREEN (-7548 3375);
DISPLAY INVISIBLE (-7548 3375);
FORCEADD TAP..1
R 2
(-7550 3425);
FORCEPROP 3 LASTPIN (-7500 3425) SIG_NAME M_J_CPU1_SB_CB<6>
J 0
(-7490 3435);
DISPLAY 0.659574 (-7490 3435);
PAINT MONO (-7490 3435);
DISPLAY INVISIBLE (-7490 3435);
FORCEPROP 1 LASTPIN (-7500 3425) BN 6
J 2
(-7488 3433);
DISPLAY 0.489362 (-7488 3433);
PAINT GREEN (-7488 3433);
FORCEPROP 2 LAST CDS_LIB mstr_standard
J 0
(-7550 3425);
DISPLAY 0.723404 (-7550 3425);
PAINT MONO (-7550 3425);
DISPLAY INVISIBLE (-7550 3425);
FORCEPROP 1 LAST BODY_TYPE PLUMBING
J 2
(-7550 3475);
DISPLAY 0.872340 (-7550 3475);
PAINT GREEN (-7550 3475);
DISPLAY INVISIBLE (-7550 3475);
FORCEPROP 1 LAST HDL_TAP TRUE
J 2
(-7875 3300);
DISPLAY 0.872340 (-7875 3300);
DISPLAY INVISIBLE (-7875 3300);
FORCEPROP 1 LAST PATH I29
J 2
(-7548 3425);
DISPLAY 0.872340 (-7548 3425);
PAINT GREEN (-7548 3425);
DISPLAY INVISIBLE (-7548 3425);
FORCEADD TAP..1
R 2
(-7550 3475);
FORCEPROP 3 LASTPIN (-7500 3475) SIG_NAME M_J_CPU1_SB_CB<7>
J 0
(-7490 3485);
DISPLAY 0.659574 (-7490 3485);
PAINT MONO (-7490 3485);
DISPLAY INVISIBLE (-7490 3485);
FORCEPROP 1 LASTPIN (-7500 3475) BN 7
J 2
(-7488 3483);
DISPLAY 0.489362 (-7488 3483);
PAINT GREEN (-7488 3483);
FORCEPROP 2 LAST CDS_LIB mstr_standard
J 0
(-7550 3475);
DISPLAY 0.723404 (-7550 3475);
PAINT MONO (-7550 3475);
DISPLAY INVISIBLE (-7550 3475);
FORCEPROP 1 LAST BODY_TYPE PLUMBING
J 2
(-7550 3525);
DISPLAY 0.872340 (-7550 3525);
PAINT GREEN (-7550 3525);
DISPLAY INVISIBLE (-7550 3525);
FORCEPROP 1 LAST HDL_TAP TRUE
J 2
(-7875 3350);
DISPLAY 0.872340 (-7875 3350);
DISPLAY INVISIBLE (-7875 3350);
FORCEPROP 1 LAST PATH I30
J 2
(-7548 3475);
DISPLAY 0.872340 (-7548 3475);
PAINT GREEN (-7548 3475);
DISPLAY INVISIBLE (-7548 3475);
FORCEADD TAP..1
R 2
(-7550 3575);
FORCEPROP 3 LASTPIN (-7500 3575) SIG_NAME M_J_CPU1_SA_CB<0>
J 0
(-7490 3585);
DISPLAY 0.659574 (-7490 3585);
PAINT MONO (-7490 3585);
DISPLAY INVISIBLE (-7490 3585);
FORCEPROP 1 LASTPIN (-7500 3575) BN 0
J 2
(-7488 3583);
DISPLAY 0.489362 (-7488 3583);
PAINT GREEN (-7488 3583);
FORCEPROP 2 LAST CDS_LIB mstr_standard
J 0
(-7550 3575);
DISPLAY 0.723404 (-7550 3575);
PAINT MONO (-7550 3575);
DISPLAY INVISIBLE (-7550 3575);
FORCEPROP 1 LAST BODY_TYPE PLUMBING
J 2
(-7550 3625);
DISPLAY 0.872340 (-7550 3625);
PAINT GREEN (-7550 3625);
DISPLAY INVISIBLE (-7550 3625);
FORCEPROP 1 LAST HDL_TAP TRUE
J 2
(-7875 3450);
DISPLAY 0.872340 (-7875 3450);
DISPLAY INVISIBLE (-7875 3450);
FORCEPROP 1 LAST PATH I31
J 2
(-7548 3575);
DISPLAY 0.872340 (-7548 3575);
PAINT GREEN (-7548 3575);
DISPLAY INVISIBLE (-7548 3575);
FORCEADD TAP..1
R 2
(-7550 3625);
FORCEPROP 3 LASTPIN (-7500 3625) SIG_NAME M_J_CPU1_SA_CB<1>
J 0
(-7490 3635);
DISPLAY 0.659574 (-7490 3635);
PAINT MONO (-7490 3635);
DISPLAY INVISIBLE (-7490 3635);
FORCEPROP 1 LASTPIN (-7500 3625) BN 1
J 2
(-7488 3633);
DISPLAY 0.489362 (-7488 3633);
PAINT GREEN (-7488 3633);
FORCEPROP 2 LAST CDS_LIB mstr_standard
J 0
(-7550 3625);
DISPLAY 0.723404 (-7550 3625);
PAINT MONO (-7550 3625);
DISPLAY INVISIBLE (-7550 3625);
FORCEPROP 1 LAST BODY_TYPE PLUMBING
J 2
(-7550 3675);
DISPLAY 0.872340 (-7550 3675);
PAINT GREEN (-7550 3675);
DISPLAY INVISIBLE (-7550 3675);
FORCEPROP 1 LAST HDL_TAP TRUE
J 2
(-7875 3500);
DISPLAY 0.872340 (-7875 3500);
DISPLAY INVISIBLE (-7875 3500);
FORCEPROP 1 LAST PATH I32
J 2
(-7548 3625);
DISPLAY 0.872340 (-7548 3625);
PAINT GREEN (-7548 3625);
DISPLAY INVISIBLE (-7548 3625);
FORCEADD TAP..1
R 2
(-7550 3675);
FORCEPROP 3 LASTPIN (-7500 3675) SIG_NAME M_J_CPU1_SA_CB<2>
J 0
(-7490 3685);
DISPLAY 0.659574 (-7490 3685);
PAINT MONO (-7490 3685);
DISPLAY INVISIBLE (-7490 3685);
FORCEPROP 1 LASTPIN (-7500 3675) BN 2
J 2
(-7488 3683);
DISPLAY 0.489362 (-7488 3683);
PAINT GREEN (-7488 3683);
FORCEPROP 2 LAST CDS_LIB mstr_standard
J 0
(-7550 3675);
DISPLAY 0.723404 (-7550 3675);
PAINT MONO (-7550 3675);
DISPLAY INVISIBLE (-7550 3675);
FORCEPROP 1 LAST BODY_TYPE PLUMBING
J 2
(-7550 3725);
DISPLAY 0.872340 (-7550 3725);
PAINT GREEN (-7550 3725);
DISPLAY INVISIBLE (-7550 3725);
FORCEPROP 1 LAST HDL_TAP TRUE
J 2
(-7875 3550);
DISPLAY 0.872340 (-7875 3550);
DISPLAY INVISIBLE (-7875 3550);
FORCEPROP 1 LAST PATH I33
J 2
(-7548 3675);
DISPLAY 0.872340 (-7548 3675);
PAINT GREEN (-7548 3675);
DISPLAY INVISIBLE (-7548 3675);
FORCEADD TAP..1
R 2
(-7550 3725);
FORCEPROP 3 LASTPIN (-7500 3725) SIG_NAME M_J_CPU1_SA_CB<3>
J 0
(-7490 3735);
DISPLAY 0.659574 (-7490 3735);
PAINT MONO (-7490 3735);
DISPLAY INVISIBLE (-7490 3735);
FORCEPROP 1 LASTPIN (-7500 3725) BN 3
J 2
(-7488 3733);
DISPLAY 0.489362 (-7488 3733);
PAINT GREEN (-7488 3733);
FORCEPROP 2 LAST CDS_LIB mstr_standard
J 0
(-7550 3725);
DISPLAY 0.723404 (-7550 3725);
PAINT MONO (-7550 3725);
DISPLAY INVISIBLE (-7550 3725);
FORCEPROP 1 LAST BODY_TYPE PLUMBING
J 2
(-7550 3775);
DISPLAY 0.872340 (-7550 3775);
PAINT GREEN (-7550 3775);
DISPLAY INVISIBLE (-7550 3775);
FORCEPROP 1 LAST HDL_TAP TRUE
J 2
(-7875 3600);
DISPLAY 0.872340 (-7875 3600);
DISPLAY INVISIBLE (-7875 3600);
FORCEPROP 1 LAST PATH I34
J 2
(-7548 3725);
DISPLAY 0.872340 (-7548 3725);
PAINT GREEN (-7548 3725);
DISPLAY INVISIBLE (-7548 3725);
FORCEADD TAP..1
R 2
(-7550 3825);
FORCEPROP 3 LASTPIN (-7500 3825) SIG_NAME M_J_CPU1_SA_CB<5>
J 0
(-7490 3835);
DISPLAY 0.659574 (-7490 3835);
PAINT MONO (-7490 3835);
DISPLAY INVISIBLE (-7490 3835);
FORCEPROP 1 LASTPIN (-7500 3825) BN 5
J 2
(-7488 3833);
DISPLAY 0.489362 (-7488 3833);
PAINT GREEN (-7488 3833);
FORCEPROP 2 LAST CDS_LIB mstr_standard
J 0
(-7550 3825);
DISPLAY 0.723404 (-7550 3825);
PAINT MONO (-7550 3825);
DISPLAY INVISIBLE (-7550 3825);
FORCEPROP 1 LAST BODY_TYPE PLUMBING
J 2
(-7550 3875);
DISPLAY 0.872340 (-7550 3875);
PAINT GREEN (-7550 3875);
DISPLAY INVISIBLE (-7550 3875);
FORCEPROP 1 LAST HDL_TAP TRUE
J 2
(-7875 3700);
DISPLAY 0.872340 (-7875 3700);
DISPLAY INVISIBLE (-7875 3700);
FORCEPROP 1 LAST PATH I35
J 2
(-7548 3825);
DISPLAY 0.872340 (-7548 3825);
PAINT GREEN (-7548 3825);
DISPLAY INVISIBLE (-7548 3825);
FORCEADD TAP..1
R 2
(-7550 3775);
FORCEPROP 3 LASTPIN (-7500 3775) SIG_NAME M_J_CPU1_SA_CB<4>
J 0
(-7490 3785);
DISPLAY 0.659574 (-7490 3785);
PAINT MONO (-7490 3785);
DISPLAY INVISIBLE (-7490 3785);
FORCEPROP 1 LASTPIN (-7500 3775) BN 4
J 2
(-7488 3783);
DISPLAY 0.489362 (-7488 3783);
PAINT GREEN (-7488 3783);
FORCEPROP 2 LAST CDS_LIB mstr_standard
J 0
(-7550 3775);
DISPLAY 0.723404 (-7550 3775);
PAINT MONO (-7550 3775);
DISPLAY INVISIBLE (-7550 3775);
FORCEPROP 1 LAST BODY_TYPE PLUMBING
J 2
(-7550 3825);
DISPLAY 0.872340 (-7550 3825);
PAINT GREEN (-7550 3825);
DISPLAY INVISIBLE (-7550 3825);
FORCEPROP 1 LAST HDL_TAP TRUE
J 2
(-7875 3650);
DISPLAY 0.872340 (-7875 3650);
DISPLAY INVISIBLE (-7875 3650);
FORCEPROP 1 LAST PATH I36
J 2
(-7548 3775);
DISPLAY 0.872340 (-7548 3775);
PAINT GREEN (-7548 3775);
DISPLAY INVISIBLE (-7548 3775);
FORCEADD TAP..1
(-5850 2125);
FORCEPROP 3 LASTPIN (-5900 2125) SIG_NAME M_J_CPU1_SB_DQ<0>
J 0
(-5890 2135);
DISPLAY 0.659574 (-5890 2135);
PAINT MONO (-5890 2135);
DISPLAY INVISIBLE (-5890 2135);
FORCEPROP 1 LASTPIN (-5900 2125) BN 0
J 0
(-5912 2133);
DISPLAY 0.489362 (-5912 2133);
PAINT GREEN (-5912 2133);
FORCEPROP 2 LAST CDS_LIB mstr_standard
J 0
(-5850 2125);
DISPLAY 0.723404 (-5850 2125);
PAINT MONO (-5850 2125);
DISPLAY INVISIBLE (-5850 2125);
FORCEPROP 1 LAST BODY_TYPE PLUMBING
J 0
(-5850 2175);
DISPLAY 0.872340 (-5850 2175);
PAINT GREEN (-5850 2175);
DISPLAY INVISIBLE (-5850 2175);
FORCEPROP 1 LAST HDL_TAP TRUE
J 0
(-5525 2000);
DISPLAY 0.872340 (-5525 2000);
DISPLAY INVISIBLE (-5525 2000);
FORCEPROP 1 LAST PATH I37
J 0
(-5852 2125);
DISPLAY 0.872340 (-5852 2125);
PAINT GREEN (-5852 2125);
DISPLAY INVISIBLE (-5852 2125);
FORCEADD TAP..1
(-5850 2175);
FORCEPROP 3 LASTPIN (-5900 2175) SIG_NAME M_J_CPU1_SB_DQ<1>
J 0
(-5890 2185);
DISPLAY 0.659574 (-5890 2185);
PAINT MONO (-5890 2185);
DISPLAY INVISIBLE (-5890 2185);
FORCEPROP 1 LASTPIN (-5900 2175) BN 1
J 0
(-5912 2183);
DISPLAY 0.489362 (-5912 2183);
PAINT GREEN (-5912 2183);
FORCEPROP 2 LAST CDS_LIB mstr_standard
J 0
(-5850 2175);
DISPLAY 0.723404 (-5850 2175);
PAINT MONO (-5850 2175);
DISPLAY INVISIBLE (-5850 2175);
FORCEPROP 1 LAST BODY_TYPE PLUMBING
J 0
(-5850 2225);
DISPLAY 0.872340 (-5850 2225);
PAINT GREEN (-5850 2225);
DISPLAY INVISIBLE (-5850 2225);
FORCEPROP 1 LAST HDL_TAP TRUE
J 0
(-5525 2050);
DISPLAY 0.872340 (-5525 2050);
DISPLAY INVISIBLE (-5525 2050);
FORCEPROP 1 LAST PATH I38
J 0
(-5852 2175);
DISPLAY 0.872340 (-5852 2175);
PAINT GREEN (-5852 2175);
DISPLAY INVISIBLE (-5852 2175);
FORCEADD TAP..1
(-5850 2225);
FORCEPROP 3 LASTPIN (-5900 2225) SIG_NAME M_J_CPU1_SB_DQ<2>
J 0
(-5890 2235);
DISPLAY 0.659574 (-5890 2235);
PAINT MONO (-5890 2235);
DISPLAY INVISIBLE (-5890 2235);
FORCEPROP 1 LASTPIN (-5900 2225) BN 2
J 0
(-5912 2233);
DISPLAY 0.489362 (-5912 2233);
PAINT GREEN (-5912 2233);
FORCEPROP 2 LAST CDS_LIB mstr_standard
J 0
(-5850 2225);
DISPLAY 0.723404 (-5850 2225);
PAINT MONO (-5850 2225);
DISPLAY INVISIBLE (-5850 2225);
FORCEPROP 1 LAST BODY_TYPE PLUMBING
J 0
(-5850 2275);
DISPLAY 0.872340 (-5850 2275);
PAINT GREEN (-5850 2275);
DISPLAY INVISIBLE (-5850 2275);
FORCEPROP 1 LAST HDL_TAP TRUE
J 0
(-5525 2100);
DISPLAY 0.872340 (-5525 2100);
DISPLAY INVISIBLE (-5525 2100);
FORCEPROP 1 LAST PATH I39
J 0
(-5852 2225);
DISPLAY 0.872340 (-5852 2225);
PAINT GREEN (-5852 2225);
DISPLAY INVISIBLE (-5852 2225);
FORCEADD OFFPAGE..1
(-8400 2825);
FORCEPROP 2 LAST $XR0 107 
J 0
(-8652 2825);
DISPLAY 0.638298 (-8652 2825);
PAINT MONO (-8652 2825);
FORCEPROP 2 LAST CDS_LIB mstr_standard
J 0
(-8400 2825);
DISPLAY 0.808511 (-8400 2825);
DISPLAY INVISIBLE (-8400 2825);
FORCEPROP 1 LAST OFFPAGE TRUE
J 0
(-8075 2700);
DISPLAY 0.872340 (-8075 2700);
PAINT GREEN (-8075 2700);
DISPLAY INVISIBLE (-8075 2700);
FORCEPROP 1 LAST COMMENT_BODY TRUE
J 0
(-8275 2725);
DISPLAY 0.872340 (-8275 2725);
PAINT GREEN (-8275 2725);
DISPLAY INVISIBLE (-8275 2725);
FORCEPROP 2 LAST PATH I4
J 0
(-8650 2875);
DISPLAY 1.021277 (-8650 2875);
DISPLAY INVISIBLE (-8650 2875);
FORCEADD TAP..1
(-5850 2275);
FORCEPROP 3 LASTPIN (-5900 2275) SIG_NAME M_J_CPU1_SB_DQ<3>
J 0
(-5890 2285);
DISPLAY 0.659574 (-5890 2285);
PAINT MONO (-5890 2285);
DISPLAY INVISIBLE (-5890 2285);
FORCEPROP 1 LASTPIN (-5900 2275) BN 3
J 0
(-5912 2283);
DISPLAY 0.489362 (-5912 2283);
PAINT GREEN (-5912 2283);
FORCEPROP 2 LAST CDS_LIB mstr_standard
J 0
(-5850 2275);
DISPLAY 0.723404 (-5850 2275);
PAINT MONO (-5850 2275);
DISPLAY INVISIBLE (-5850 2275);
FORCEPROP 1 LAST BODY_TYPE PLUMBING
J 0
(-5850 2325);
DISPLAY 0.872340 (-5850 2325);
PAINT GREEN (-5850 2325);
DISPLAY INVISIBLE (-5850 2325);
FORCEPROP 1 LAST HDL_TAP TRUE
J 0
(-5525 2150);
DISPLAY 0.872340 (-5525 2150);
DISPLAY INVISIBLE (-5525 2150);
FORCEPROP 1 LAST PATH I40
J 0
(-5852 2275);
DISPLAY 0.872340 (-5852 2275);
PAINT GREEN (-5852 2275);
DISPLAY INVISIBLE (-5852 2275);
FORCEADD TAP..1
(-5850 2325);
FORCEPROP 3 LASTPIN (-5900 2325) SIG_NAME M_J_CPU1_SB_DQ<4>
J 0
(-5890 2335);
DISPLAY 0.659574 (-5890 2335);
PAINT MONO (-5890 2335);
DISPLAY INVISIBLE (-5890 2335);
FORCEPROP 1 LASTPIN (-5900 2325) BN 4
J 0
(-5912 2333);
DISPLAY 0.489362 (-5912 2333);
PAINT GREEN (-5912 2333);
FORCEPROP 2 LAST CDS_LIB mstr_standard
J 0
(-5850 2325);
DISPLAY 0.723404 (-5850 2325);
PAINT MONO (-5850 2325);
DISPLAY INVISIBLE (-5850 2325);
FORCEPROP 1 LAST BODY_TYPE PLUMBING
J 0
(-5850 2375);
DISPLAY 0.872340 (-5850 2375);
PAINT GREEN (-5850 2375);
DISPLAY INVISIBLE (-5850 2375);
FORCEPROP 1 LAST HDL_TAP TRUE
J 0
(-5525 2200);
DISPLAY 0.872340 (-5525 2200);
DISPLAY INVISIBLE (-5525 2200);
FORCEPROP 1 LAST PATH I41
J 0
(-5852 2325);
DISPLAY 0.872340 (-5852 2325);
PAINT GREEN (-5852 2325);
DISPLAY INVISIBLE (-5852 2325);
FORCEADD TAP..1
(-5850 2425);
FORCEPROP 3 LASTPIN (-5900 2425) SIG_NAME M_J_CPU1_SB_DQ<6>
J 0
(-5890 2435);
DISPLAY 0.659574 (-5890 2435);
PAINT MONO (-5890 2435);
DISPLAY INVISIBLE (-5890 2435);
FORCEPROP 1 LASTPIN (-5900 2425) BN 6
J 0
(-5912 2433);
DISPLAY 0.489362 (-5912 2433);
PAINT GREEN (-5912 2433);
FORCEPROP 2 LAST CDS_LIB mstr_standard
J 0
(-5850 2425);
DISPLAY 0.723404 (-5850 2425);
PAINT MONO (-5850 2425);
DISPLAY INVISIBLE (-5850 2425);
FORCEPROP 1 LAST BODY_TYPE PLUMBING
J 0
(-5850 2475);
DISPLAY 0.872340 (-5850 2475);
PAINT GREEN (-5850 2475);
DISPLAY INVISIBLE (-5850 2475);
FORCEPROP 1 LAST HDL_TAP TRUE
J 0
(-5525 2300);
DISPLAY 0.872340 (-5525 2300);
DISPLAY INVISIBLE (-5525 2300);
FORCEPROP 1 LAST PATH I42
J 0
(-5852 2425);
DISPLAY 0.872340 (-5852 2425);
PAINT GREEN (-5852 2425);
DISPLAY INVISIBLE (-5852 2425);
FORCEADD TAP..1
(-5850 2375);
FORCEPROP 3 LASTPIN (-5900 2375) SIG_NAME M_J_CPU1_SB_DQ<5>
J 0
(-5890 2385);
DISPLAY 0.659574 (-5890 2385);
PAINT MONO (-5890 2385);
DISPLAY INVISIBLE (-5890 2385);
FORCEPROP 1 LASTPIN (-5900 2375) BN 5
J 0
(-5912 2383);
DISPLAY 0.489362 (-5912 2383);
PAINT GREEN (-5912 2383);
FORCEPROP 2 LAST CDS_LIB mstr_standard
J 0
(-5850 2375);
DISPLAY 0.723404 (-5850 2375);
PAINT MONO (-5850 2375);
DISPLAY INVISIBLE (-5850 2375);
FORCEPROP 1 LAST BODY_TYPE PLUMBING
J 0
(-5850 2425);
DISPLAY 0.872340 (-5850 2425);
PAINT GREEN (-5850 2425);
DISPLAY INVISIBLE (-5850 2425);
FORCEPROP 1 LAST HDL_TAP TRUE
J 0
(-5525 2250);
DISPLAY 0.872340 (-5525 2250);
DISPLAY INVISIBLE (-5525 2250);
FORCEPROP 1 LAST PATH I43
J 0
(-5852 2375);
DISPLAY 0.872340 (-5852 2375);
PAINT GREEN (-5852 2375);
DISPLAY INVISIBLE (-5852 2375);
FORCEADD TAP..1
(-5850 2525);
FORCEPROP 3 LASTPIN (-5900 2525) SIG_NAME M_J_CPU1_SB_DQ<8>
J 0
(-5890 2535);
DISPLAY 0.659574 (-5890 2535);
PAINT MONO (-5890 2535);
DISPLAY INVISIBLE (-5890 2535);
FORCEPROP 1 LASTPIN (-5900 2525) BN 8
J 0
(-5912 2533);
DISPLAY 0.489362 (-5912 2533);
PAINT GREEN (-5912 2533);
FORCEPROP 2 LAST CDS_LIB mstr_standard
J 0
(-5850 2525);
DISPLAY 0.723404 (-5850 2525);
PAINT MONO (-5850 2525);
DISPLAY INVISIBLE (-5850 2525);
FORCEPROP 1 LAST BODY_TYPE PLUMBING
J 0
(-5850 2575);
DISPLAY 0.872340 (-5850 2575);
PAINT GREEN (-5850 2575);
DISPLAY INVISIBLE (-5850 2575);
FORCEPROP 1 LAST HDL_TAP TRUE
J 0
(-5525 2400);
DISPLAY 0.872340 (-5525 2400);
DISPLAY INVISIBLE (-5525 2400);
FORCEPROP 1 LAST PATH I44
J 0
(-5852 2525);
DISPLAY 0.872340 (-5852 2525);
PAINT GREEN (-5852 2525);
DISPLAY INVISIBLE (-5852 2525);
FORCEADD TAP..1
(-5850 2475);
FORCEPROP 3 LASTPIN (-5900 2475) SIG_NAME M_J_CPU1_SB_DQ<7>
J 0
(-5890 2485);
DISPLAY 0.659574 (-5890 2485);
PAINT MONO (-5890 2485);
DISPLAY INVISIBLE (-5890 2485);
FORCEPROP 1 LASTPIN (-5900 2475) BN 7
J 0
(-5912 2483);
DISPLAY 0.489362 (-5912 2483);
PAINT GREEN (-5912 2483);
FORCEPROP 2 LAST CDS_LIB mstr_standard
J 0
(-5850 2475);
DISPLAY 0.723404 (-5850 2475);
PAINT MONO (-5850 2475);
DISPLAY INVISIBLE (-5850 2475);
FORCEPROP 1 LAST BODY_TYPE PLUMBING
J 0
(-5850 2525);
DISPLAY 0.872340 (-5850 2525);
PAINT GREEN (-5850 2525);
DISPLAY INVISIBLE (-5850 2525);
FORCEPROP 1 LAST HDL_TAP TRUE
J 0
(-5525 2350);
DISPLAY 0.872340 (-5525 2350);
DISPLAY INVISIBLE (-5525 2350);
FORCEPROP 1 LAST PATH I45
J 0
(-5852 2475);
DISPLAY 0.872340 (-5852 2475);
PAINT GREEN (-5852 2475);
DISPLAY INVISIBLE (-5852 2475);
FORCEADD TAP..1
(-5850 2575);
FORCEPROP 3 LASTPIN (-5900 2575) SIG_NAME M_J_CPU1_SB_DQ<9>
J 0
(-5890 2585);
DISPLAY 0.659574 (-5890 2585);
PAINT MONO (-5890 2585);
DISPLAY INVISIBLE (-5890 2585);
FORCEPROP 1 LASTPIN (-5900 2575) BN 9
J 0
(-5912 2583);
DISPLAY 0.489362 (-5912 2583);
PAINT GREEN (-5912 2583);
FORCEPROP 2 LAST CDS_LIB mstr_standard
J 0
(-5850 2575);
DISPLAY 0.723404 (-5850 2575);
PAINT MONO (-5850 2575);
DISPLAY INVISIBLE (-5850 2575);
FORCEPROP 1 LAST BODY_TYPE PLUMBING
J 0
(-5850 2625);
DISPLAY 0.872340 (-5850 2625);
PAINT GREEN (-5850 2625);
DISPLAY INVISIBLE (-5850 2625);
FORCEPROP 1 LAST HDL_TAP TRUE
J 0
(-5525 2450);
DISPLAY 0.872340 (-5525 2450);
DISPLAY INVISIBLE (-5525 2450);
FORCEPROP 1 LAST PATH I46
J 0
(-5852 2575);
DISPLAY 0.872340 (-5852 2575);
PAINT GREEN (-5852 2575);
DISPLAY INVISIBLE (-5852 2575);
FORCEADD TAP..1
(-5850 2675);
FORCEPROP 3 LASTPIN (-5900 2675) SIG_NAME M_J_CPU1_SB_DQ<11>
J 0
(-5890 2685);
DISPLAY 0.659574 (-5890 2685);
PAINT MONO (-5890 2685);
DISPLAY INVISIBLE (-5890 2685);
FORCEPROP 1 LASTPIN (-5900 2675) BN 11
J 0
(-5912 2683);
DISPLAY 0.489362 (-5912 2683);
PAINT GREEN (-5912 2683);
FORCEPROP 2 LAST CDS_LIB mstr_standard
J 0
(-5850 2675);
DISPLAY 0.723404 (-5850 2675);
PAINT MONO (-5850 2675);
DISPLAY INVISIBLE (-5850 2675);
FORCEPROP 1 LAST BODY_TYPE PLUMBING
J 0
(-5850 2725);
DISPLAY 0.872340 (-5850 2725);
PAINT GREEN (-5850 2725);
DISPLAY INVISIBLE (-5850 2725);
FORCEPROP 1 LAST HDL_TAP TRUE
J 0
(-5525 2550);
DISPLAY 0.872340 (-5525 2550);
DISPLAY INVISIBLE (-5525 2550);
FORCEPROP 1 LAST PATH I47
J 0
(-5852 2675);
DISPLAY 0.872340 (-5852 2675);
PAINT GREEN (-5852 2675);
DISPLAY INVISIBLE (-5852 2675);
FORCEADD TAP..1
(-5850 2625);
FORCEPROP 3 LASTPIN (-5900 2625) SIG_NAME M_J_CPU1_SB_DQ<10>
J 0
(-5890 2635);
DISPLAY 0.659574 (-5890 2635);
PAINT MONO (-5890 2635);
DISPLAY INVISIBLE (-5890 2635);
FORCEPROP 1 LASTPIN (-5900 2625) BN 10
J 0
(-5912 2633);
DISPLAY 0.489362 (-5912 2633);
PAINT GREEN (-5912 2633);
FORCEPROP 2 LAST CDS_LIB mstr_standard
J 0
(-5850 2625);
DISPLAY 0.723404 (-5850 2625);
PAINT MONO (-5850 2625);
DISPLAY INVISIBLE (-5850 2625);
FORCEPROP 1 LAST BODY_TYPE PLUMBING
J 0
(-5850 2675);
DISPLAY 0.872340 (-5850 2675);
PAINT GREEN (-5850 2675);
DISPLAY INVISIBLE (-5850 2675);
FORCEPROP 1 LAST HDL_TAP TRUE
J 0
(-5525 2500);
DISPLAY 0.872340 (-5525 2500);
DISPLAY INVISIBLE (-5525 2500);
FORCEPROP 1 LAST PATH I48
J 0
(-5852 2625);
DISPLAY 0.872340 (-5852 2625);
PAINT GREEN (-5852 2625);
DISPLAY INVISIBLE (-5852 2625);
FORCEADD TAP..1
(-5850 2725);
FORCEPROP 3 LASTPIN (-5900 2725) SIG_NAME M_J_CPU1_SB_DQ<12>
J 0
(-5890 2735);
DISPLAY 0.659574 (-5890 2735);
PAINT MONO (-5890 2735);
DISPLAY INVISIBLE (-5890 2735);
FORCEPROP 1 LASTPIN (-5900 2725) BN 12
J 0
(-5912 2733);
DISPLAY 0.489362 (-5912 2733);
PAINT GREEN (-5912 2733);
FORCEPROP 2 LAST CDS_LIB mstr_standard
J 0
(-5850 2725);
DISPLAY 0.723404 (-5850 2725);
PAINT MONO (-5850 2725);
DISPLAY INVISIBLE (-5850 2725);
FORCEPROP 1 LAST BODY_TYPE PLUMBING
J 0
(-5850 2775);
DISPLAY 0.872340 (-5850 2775);
PAINT GREEN (-5850 2775);
DISPLAY INVISIBLE (-5850 2775);
FORCEPROP 1 LAST HDL_TAP TRUE
J 0
(-5525 2600);
DISPLAY 0.872340 (-5525 2600);
DISPLAY INVISIBLE (-5525 2600);
FORCEPROP 1 LAST PATH I49
J 0
(-5852 2725);
DISPLAY 0.872340 (-5852 2725);
PAINT GREEN (-5852 2725);
DISPLAY INVISIBLE (-5852 2725);
FORCEADD OFFPAGE..5
(-8150 1925);
FORCEPROP 2 LAST $XR0 46 
J 0
(-8374 1925);
DISPLAY 0.638298 (-8374 1925);
PAINT MONO (-8374 1925);
FORCEPROP 2 LAST CDS_LIB mstr_standard
J 0
(-8150 1925);
DISPLAY 0.808511 (-8150 1925);
DISPLAY INVISIBLE (-8150 1925);
FORCEPROP 1 LAST OFFPAGE TRUE
J 0
(-7825 1800);
DISPLAY 0.872340 (-7825 1800);
PAINT GREEN (-7825 1800);
DISPLAY INVISIBLE (-7825 1800);
FORCEPROP 1 LAST COMMENT_BODY TRUE
J 0
(-8050 1850);
DISPLAY 0.872340 (-8050 1850);
PAINT GREEN (-8050 1850);
DISPLAY INVISIBLE (-8050 1850);
FORCEPROP 2 LAST PATH I5
J 0
(-8350 1975);
DISPLAY 1.021277 (-8350 1975);
DISPLAY INVISIBLE (-8350 1975);
FORCEADD TAP..1
(-5850 2775);
FORCEPROP 3 LASTPIN (-5900 2775) SIG_NAME M_J_CPU1_SB_DQ<13>
J 0
(-5890 2785);
DISPLAY 0.659574 (-5890 2785);
PAINT MONO (-5890 2785);
DISPLAY INVISIBLE (-5890 2785);
FORCEPROP 1 LASTPIN (-5900 2775) BN 13
J 0
(-5912 2783);
DISPLAY 0.489362 (-5912 2783);
PAINT GREEN (-5912 2783);
FORCEPROP 2 LAST CDS_LIB mstr_standard
J 0
(-5850 2775);
DISPLAY 0.723404 (-5850 2775);
PAINT MONO (-5850 2775);
DISPLAY INVISIBLE (-5850 2775);
FORCEPROP 1 LAST BODY_TYPE PLUMBING
J 0
(-5850 2825);
DISPLAY 0.872340 (-5850 2825);
PAINT GREEN (-5850 2825);
DISPLAY INVISIBLE (-5850 2825);
FORCEPROP 1 LAST HDL_TAP TRUE
J 0
(-5525 2650);
DISPLAY 0.872340 (-5525 2650);
DISPLAY INVISIBLE (-5525 2650);
FORCEPROP 1 LAST PATH I50
J 0
(-5852 2775);
DISPLAY 0.872340 (-5852 2775);
PAINT GREEN (-5852 2775);
DISPLAY INVISIBLE (-5852 2775);
FORCEADD TAP..1
(-5850 2825);
FORCEPROP 3 LASTPIN (-5900 2825) SIG_NAME M_J_CPU1_SB_DQ<14>
J 0
(-5890 2835);
DISPLAY 0.659574 (-5890 2835);
PAINT MONO (-5890 2835);
DISPLAY INVISIBLE (-5890 2835);
FORCEPROP 1 LASTPIN (-5900 2825) BN 14
J 0
(-5912 2833);
DISPLAY 0.489362 (-5912 2833);
PAINT GREEN (-5912 2833);
FORCEPROP 2 LAST CDS_LIB mstr_standard
J 0
(-5850 2825);
DISPLAY 0.723404 (-5850 2825);
PAINT MONO (-5850 2825);
DISPLAY INVISIBLE (-5850 2825);
FORCEPROP 1 LAST BODY_TYPE PLUMBING
J 0
(-5850 2875);
DISPLAY 0.872340 (-5850 2875);
PAINT GREEN (-5850 2875);
DISPLAY INVISIBLE (-5850 2875);
FORCEPROP 1 LAST HDL_TAP TRUE
J 0
(-5525 2700);
DISPLAY 0.872340 (-5525 2700);
DISPLAY INVISIBLE (-5525 2700);
FORCEPROP 1 LAST PATH I51
J 0
(-5852 2825);
DISPLAY 0.872340 (-5852 2825);
PAINT GREEN (-5852 2825);
DISPLAY INVISIBLE (-5852 2825);
FORCEADD TAP..1
(-5850 2925);
FORCEPROP 3 LASTPIN (-5900 2925) SIG_NAME M_J_CPU1_SB_DQ<16>
J 0
(-5890 2935);
DISPLAY 0.659574 (-5890 2935);
PAINT MONO (-5890 2935);
DISPLAY INVISIBLE (-5890 2935);
FORCEPROP 1 LASTPIN (-5900 2925) BN 16
J 0
(-5912 2933);
DISPLAY 0.489362 (-5912 2933);
PAINT GREEN (-5912 2933);
FORCEPROP 2 LAST CDS_LIB mstr_standard
J 0
(-5850 2925);
DISPLAY 0.723404 (-5850 2925);
PAINT MONO (-5850 2925);
DISPLAY INVISIBLE (-5850 2925);
FORCEPROP 1 LAST BODY_TYPE PLUMBING
J 0
(-5850 2975);
DISPLAY 0.872340 (-5850 2975);
PAINT GREEN (-5850 2975);
DISPLAY INVISIBLE (-5850 2975);
FORCEPROP 1 LAST HDL_TAP TRUE
J 0
(-5525 2800);
DISPLAY 0.872340 (-5525 2800);
DISPLAY INVISIBLE (-5525 2800);
FORCEPROP 1 LAST PATH I52
J 0
(-5852 2925);
DISPLAY 0.872340 (-5852 2925);
PAINT GREEN (-5852 2925);
DISPLAY INVISIBLE (-5852 2925);
FORCEADD TAP..1
(-5850 2875);
FORCEPROP 3 LASTPIN (-5900 2875) SIG_NAME M_J_CPU1_SB_DQ<15>
J 0
(-5890 2885);
DISPLAY 0.659574 (-5890 2885);
PAINT MONO (-5890 2885);
DISPLAY INVISIBLE (-5890 2885);
FORCEPROP 1 LASTPIN (-5900 2875) BN 15
J 0
(-5912 2883);
DISPLAY 0.489362 (-5912 2883);
PAINT GREEN (-5912 2883);
FORCEPROP 2 LAST CDS_LIB mstr_standard
J 0
(-5850 2875);
DISPLAY 0.723404 (-5850 2875);
PAINT MONO (-5850 2875);
DISPLAY INVISIBLE (-5850 2875);
FORCEPROP 1 LAST BODY_TYPE PLUMBING
J 0
(-5850 2925);
DISPLAY 0.872340 (-5850 2925);
PAINT GREEN (-5850 2925);
DISPLAY INVISIBLE (-5850 2925);
FORCEPROP 1 LAST HDL_TAP TRUE
J 0
(-5525 2750);
DISPLAY 0.872340 (-5525 2750);
DISPLAY INVISIBLE (-5525 2750);
FORCEPROP 1 LAST PATH I53
J 0
(-5852 2875);
DISPLAY 0.872340 (-5852 2875);
PAINT GREEN (-5852 2875);
DISPLAY INVISIBLE (-5852 2875);
FORCEADD TAP..1
(-5850 2975);
FORCEPROP 3 LASTPIN (-5900 2975) SIG_NAME M_J_CPU1_SB_DQ<17>
J 0
(-5890 2985);
DISPLAY 0.659574 (-5890 2985);
PAINT MONO (-5890 2985);
DISPLAY INVISIBLE (-5890 2985);
FORCEPROP 1 LASTPIN (-5900 2975) BN 17
J 0
(-5912 2983);
DISPLAY 0.489362 (-5912 2983);
PAINT GREEN (-5912 2983);
FORCEPROP 2 LAST CDS_LIB mstr_standard
J 0
(-5850 2975);
DISPLAY 0.723404 (-5850 2975);
PAINT MONO (-5850 2975);
DISPLAY INVISIBLE (-5850 2975);
FORCEPROP 1 LAST BODY_TYPE PLUMBING
J 0
(-5850 3025);
DISPLAY 0.872340 (-5850 3025);
PAINT GREEN (-5850 3025);
DISPLAY INVISIBLE (-5850 3025);
FORCEPROP 1 LAST HDL_TAP TRUE
J 0
(-5525 2850);
DISPLAY 0.872340 (-5525 2850);
DISPLAY INVISIBLE (-5525 2850);
FORCEPROP 1 LAST PATH I54
J 0
(-5852 2975);
DISPLAY 0.872340 (-5852 2975);
PAINT GREEN (-5852 2975);
DISPLAY INVISIBLE (-5852 2975);
FORCEADD TAP..1
(-5850 3025);
FORCEPROP 3 LASTPIN (-5900 3025) SIG_NAME M_J_CPU1_SB_DQ<18>
J 0
(-5890 3035);
DISPLAY 0.659574 (-5890 3035);
PAINT MONO (-5890 3035);
DISPLAY INVISIBLE (-5890 3035);
FORCEPROP 1 LASTPIN (-5900 3025) BN 18
J 0
(-5912 3033);
DISPLAY 0.489362 (-5912 3033);
PAINT GREEN (-5912 3033);
FORCEPROP 2 LAST CDS_LIB mstr_standard
J 0
(-5850 3025);
DISPLAY 0.723404 (-5850 3025);
PAINT MONO (-5850 3025);
DISPLAY INVISIBLE (-5850 3025);
FORCEPROP 1 LAST BODY_TYPE PLUMBING
J 0
(-5850 3075);
DISPLAY 0.872340 (-5850 3075);
PAINT GREEN (-5850 3075);
DISPLAY INVISIBLE (-5850 3075);
FORCEPROP 1 LAST HDL_TAP TRUE
J 0
(-5525 2900);
DISPLAY 0.872340 (-5525 2900);
DISPLAY INVISIBLE (-5525 2900);
FORCEPROP 1 LAST PATH I55
J 0
(-5852 3025);
DISPLAY 0.872340 (-5852 3025);
PAINT GREEN (-5852 3025);
DISPLAY INVISIBLE (-5852 3025);
FORCEADD TAP..1
(-5850 3075);
FORCEPROP 3 LASTPIN (-5900 3075) SIG_NAME M_J_CPU1_SB_DQ<19>
J 0
(-5890 3085);
DISPLAY 0.659574 (-5890 3085);
PAINT MONO (-5890 3085);
DISPLAY INVISIBLE (-5890 3085);
FORCEPROP 1 LASTPIN (-5900 3075) BN 19
J 0
(-5912 3083);
DISPLAY 0.489362 (-5912 3083);
PAINT GREEN (-5912 3083);
FORCEPROP 2 LAST CDS_LIB mstr_standard
J 0
(-5850 3075);
DISPLAY 0.723404 (-5850 3075);
PAINT MONO (-5850 3075);
DISPLAY INVISIBLE (-5850 3075);
FORCEPROP 1 LAST BODY_TYPE PLUMBING
J 0
(-5850 3125);
DISPLAY 0.872340 (-5850 3125);
PAINT GREEN (-5850 3125);
DISPLAY INVISIBLE (-5850 3125);
FORCEPROP 1 LAST HDL_TAP TRUE
J 0
(-5525 2950);
DISPLAY 0.872340 (-5525 2950);
DISPLAY INVISIBLE (-5525 2950);
FORCEPROP 1 LAST PATH I56
J 0
(-5852 3075);
DISPLAY 0.872340 (-5852 3075);
PAINT GREEN (-5852 3075);
DISPLAY INVISIBLE (-5852 3075);
FORCEADD TAP..1
(-5850 3125);
FORCEPROP 3 LASTPIN (-5900 3125) SIG_NAME M_J_CPU1_SB_DQ<20>
J 0
(-5890 3135);
DISPLAY 0.659574 (-5890 3135);
PAINT MONO (-5890 3135);
DISPLAY INVISIBLE (-5890 3135);
FORCEPROP 1 LASTPIN (-5900 3125) BN 20
J 0
(-5912 3133);
DISPLAY 0.489362 (-5912 3133);
PAINT GREEN (-5912 3133);
FORCEPROP 2 LAST CDS_LIB mstr_standard
J 0
(-5850 3125);
DISPLAY 0.723404 (-5850 3125);
PAINT MONO (-5850 3125);
DISPLAY INVISIBLE (-5850 3125);
FORCEPROP 1 LAST BODY_TYPE PLUMBING
J 0
(-5850 3175);
DISPLAY 0.872340 (-5850 3175);
PAINT GREEN (-5850 3175);
DISPLAY INVISIBLE (-5850 3175);
FORCEPROP 1 LAST HDL_TAP TRUE
J 0
(-5525 3000);
DISPLAY 0.872340 (-5525 3000);
DISPLAY INVISIBLE (-5525 3000);
FORCEPROP 1 LAST PATH I57
J 0
(-5852 3125);
DISPLAY 0.872340 (-5852 3125);
PAINT GREEN (-5852 3125);
DISPLAY INVISIBLE (-5852 3125);
FORCEADD TAP..1
(-5850 3175);
FORCEPROP 3 LASTPIN (-5900 3175) SIG_NAME M_J_CPU1_SB_DQ<21>
J 0
(-5890 3185);
DISPLAY 0.659574 (-5890 3185);
PAINT MONO (-5890 3185);
DISPLAY INVISIBLE (-5890 3185);
FORCEPROP 1 LASTPIN (-5900 3175) BN 21
J 0
(-5912 3183);
DISPLAY 0.489362 (-5912 3183);
PAINT GREEN (-5912 3183);
FORCEPROP 2 LAST CDS_LIB mstr_standard
J 0
(-5850 3175);
DISPLAY 0.723404 (-5850 3175);
PAINT MONO (-5850 3175);
DISPLAY INVISIBLE (-5850 3175);
FORCEPROP 1 LAST BODY_TYPE PLUMBING
J 0
(-5850 3225);
DISPLAY 0.872340 (-5850 3225);
PAINT GREEN (-5850 3225);
DISPLAY INVISIBLE (-5850 3225);
FORCEPROP 1 LAST HDL_TAP TRUE
J 0
(-5525 3050);
DISPLAY 0.872340 (-5525 3050);
DISPLAY INVISIBLE (-5525 3050);
FORCEPROP 1 LAST PATH I58
J 0
(-5852 3175);
DISPLAY 0.872340 (-5852 3175);
PAINT GREEN (-5852 3175);
DISPLAY INVISIBLE (-5852 3175);
FORCEADD TAP..1
(-5850 3225);
FORCEPROP 3 LASTPIN (-5900 3225) SIG_NAME M_J_CPU1_SB_DQ<22>
J 0
(-5890 3235);
DISPLAY 0.659574 (-5890 3235);
PAINT MONO (-5890 3235);
DISPLAY INVISIBLE (-5890 3235);
FORCEPROP 1 LASTPIN (-5900 3225) BN 22
J 0
(-5912 3233);
DISPLAY 0.489362 (-5912 3233);
PAINT GREEN (-5912 3233);
FORCEPROP 2 LAST CDS_LIB mstr_standard
J 0
(-5850 3225);
DISPLAY 0.723404 (-5850 3225);
PAINT MONO (-5850 3225);
DISPLAY INVISIBLE (-5850 3225);
FORCEPROP 1 LAST BODY_TYPE PLUMBING
J 0
(-5850 3275);
DISPLAY 0.872340 (-5850 3275);
PAINT GREEN (-5850 3275);
DISPLAY INVISIBLE (-5850 3275);
FORCEPROP 1 LAST HDL_TAP TRUE
J 0
(-5525 3100);
DISPLAY 0.872340 (-5525 3100);
DISPLAY INVISIBLE (-5525 3100);
FORCEPROP 1 LAST PATH I59
J 0
(-5852 3225);
DISPLAY 0.872340 (-5852 3225);
PAINT GREEN (-5852 3225);
DISPLAY INVISIBLE (-5852 3225);
FORCEADD OFFPAGE..5
(-8150 1875);
FORCEPROP 2 LAST $XR0 46 
J 0
(-8374 1875);
DISPLAY 0.638298 (-8374 1875);
PAINT MONO (-8374 1875);
FORCEPROP 2 LAST CDS_LIB mstr_standard
J 0
(-8150 1875);
DISPLAY 0.808511 (-8150 1875);
DISPLAY INVISIBLE (-8150 1875);
FORCEPROP 1 LAST OFFPAGE TRUE
J 0
(-7825 1750);
DISPLAY 0.872340 (-7825 1750);
PAINT GREEN (-7825 1750);
DISPLAY INVISIBLE (-7825 1750);
FORCEPROP 1 LAST COMMENT_BODY TRUE
J 0
(-8050 1800);
DISPLAY 0.872340 (-8050 1800);
PAINT GREEN (-8050 1800);
DISPLAY INVISIBLE (-8050 1800);
FORCEPROP 2 LAST PATH I6
J 0
(-8350 1925);
DISPLAY 1.021277 (-8350 1925);
DISPLAY INVISIBLE (-8350 1925);
FORCEADD TAP..1
(-5850 3325);
FORCEPROP 3 LASTPIN (-5900 3325) SIG_NAME M_J_CPU1_SB_DQ<24>
J 0
(-5890 3335);
DISPLAY 0.659574 (-5890 3335);
PAINT MONO (-5890 3335);
DISPLAY INVISIBLE (-5890 3335);
FORCEPROP 1 LASTPIN (-5900 3325) BN 24
J 0
(-5912 3333);
DISPLAY 0.489362 (-5912 3333);
PAINT GREEN (-5912 3333);
FORCEPROP 2 LAST CDS_LIB mstr_standard
J 0
(-5850 3325);
DISPLAY 0.723404 (-5850 3325);
PAINT MONO (-5850 3325);
DISPLAY INVISIBLE (-5850 3325);
FORCEPROP 1 LAST BODY_TYPE PLUMBING
J 0
(-5850 3375);
DISPLAY 0.872340 (-5850 3375);
PAINT GREEN (-5850 3375);
DISPLAY INVISIBLE (-5850 3375);
FORCEPROP 1 LAST HDL_TAP TRUE
J 0
(-5525 3200);
DISPLAY 0.872340 (-5525 3200);
DISPLAY INVISIBLE (-5525 3200);
FORCEPROP 1 LAST PATH I60
J 0
(-5852 3325);
DISPLAY 0.872340 (-5852 3325);
PAINT GREEN (-5852 3325);
DISPLAY INVISIBLE (-5852 3325);
FORCEADD TAP..1
(-5850 3275);
FORCEPROP 3 LASTPIN (-5900 3275) SIG_NAME M_J_CPU1_SB_DQ<23>
J 0
(-5890 3285);
DISPLAY 0.659574 (-5890 3285);
PAINT MONO (-5890 3285);
DISPLAY INVISIBLE (-5890 3285);
FORCEPROP 1 LASTPIN (-5900 3275) BN 23
J 0
(-5912 3283);
DISPLAY 0.489362 (-5912 3283);
PAINT GREEN (-5912 3283);
FORCEPROP 2 LAST CDS_LIB mstr_standard
J 0
(-5850 3275);
DISPLAY 0.723404 (-5850 3275);
PAINT MONO (-5850 3275);
DISPLAY INVISIBLE (-5850 3275);
FORCEPROP 1 LAST BODY_TYPE PLUMBING
J 0
(-5850 3325);
DISPLAY 0.872340 (-5850 3325);
PAINT GREEN (-5850 3325);
DISPLAY INVISIBLE (-5850 3325);
FORCEPROP 1 LAST HDL_TAP TRUE
J 0
(-5525 3150);
DISPLAY 0.872340 (-5525 3150);
DISPLAY INVISIBLE (-5525 3150);
FORCEPROP 1 LAST PATH I61
J 0
(-5852 3275);
DISPLAY 0.872340 (-5852 3275);
PAINT GREEN (-5852 3275);
DISPLAY INVISIBLE (-5852 3275);
FORCEADD TAP..1
(-5850 3375);
FORCEPROP 3 LASTPIN (-5900 3375) SIG_NAME M_J_CPU1_SB_DQ<25>
J 0
(-5890 3385);
DISPLAY 0.659574 (-5890 3385);
PAINT MONO (-5890 3385);
DISPLAY INVISIBLE (-5890 3385);
FORCEPROP 1 LASTPIN (-5900 3375) BN 25
J 0
(-5912 3383);
DISPLAY 0.489362 (-5912 3383);
PAINT GREEN (-5912 3383);
FORCEPROP 2 LAST CDS_LIB mstr_standard
J 0
(-5850 3375);
DISPLAY 0.723404 (-5850 3375);
PAINT MONO (-5850 3375);
DISPLAY INVISIBLE (-5850 3375);
FORCEPROP 1 LAST BODY_TYPE PLUMBING
J 0
(-5850 3425);
DISPLAY 0.872340 (-5850 3425);
PAINT GREEN (-5850 3425);
DISPLAY INVISIBLE (-5850 3425);
FORCEPROP 1 LAST HDL_TAP TRUE
J 0
(-5525 3250);
DISPLAY 0.872340 (-5525 3250);
DISPLAY INVISIBLE (-5525 3250);
FORCEPROP 1 LAST PATH I62
J 0
(-5852 3375);
DISPLAY 0.872340 (-5852 3375);
PAINT GREEN (-5852 3375);
DISPLAY INVISIBLE (-5852 3375);
FORCEADD TAP..1
(-5850 3425);
FORCEPROP 3 LASTPIN (-5900 3425) SIG_NAME M_J_CPU1_SB_DQ<26>
J 0
(-5890 3435);
DISPLAY 0.659574 (-5890 3435);
PAINT MONO (-5890 3435);
DISPLAY INVISIBLE (-5890 3435);
FORCEPROP 1 LASTPIN (-5900 3425) BN 26
J 0
(-5912 3433);
DISPLAY 0.489362 (-5912 3433);
PAINT GREEN (-5912 3433);
FORCEPROP 2 LAST CDS_LIB mstr_standard
J 0
(-5850 3425);
DISPLAY 0.723404 (-5850 3425);
PAINT MONO (-5850 3425);
DISPLAY INVISIBLE (-5850 3425);
FORCEPROP 1 LAST BODY_TYPE PLUMBING
J 0
(-5850 3475);
DISPLAY 0.872340 (-5850 3475);
PAINT GREEN (-5850 3475);
DISPLAY INVISIBLE (-5850 3475);
FORCEPROP 1 LAST HDL_TAP TRUE
J 0
(-5525 3300);
DISPLAY 0.872340 (-5525 3300);
DISPLAY INVISIBLE (-5525 3300);
FORCEPROP 1 LAST PATH I63
J 0
(-5852 3425);
DISPLAY 0.872340 (-5852 3425);
PAINT GREEN (-5852 3425);
DISPLAY INVISIBLE (-5852 3425);
FORCEADD TAP..1
(-5850 3475);
FORCEPROP 3 LASTPIN (-5900 3475) SIG_NAME M_J_CPU1_SB_DQ<27>
J 0
(-5890 3485);
DISPLAY 0.659574 (-5890 3485);
PAINT MONO (-5890 3485);
DISPLAY INVISIBLE (-5890 3485);
FORCEPROP 1 LASTPIN (-5900 3475) BN 27
J 0
(-5912 3483);
DISPLAY 0.489362 (-5912 3483);
PAINT GREEN (-5912 3483);
FORCEPROP 2 LAST CDS_LIB mstr_standard
J 0
(-5850 3475);
DISPLAY 0.723404 (-5850 3475);
PAINT MONO (-5850 3475);
DISPLAY INVISIBLE (-5850 3475);
FORCEPROP 1 LAST BODY_TYPE PLUMBING
J 0
(-5850 3525);
DISPLAY 0.872340 (-5850 3525);
PAINT GREEN (-5850 3525);
DISPLAY INVISIBLE (-5850 3525);
FORCEPROP 1 LAST HDL_TAP TRUE
J 0
(-5525 3350);
DISPLAY 0.872340 (-5525 3350);
DISPLAY INVISIBLE (-5525 3350);
FORCEPROP 1 LAST PATH I64
J 0
(-5852 3475);
DISPLAY 0.872340 (-5852 3475);
PAINT GREEN (-5852 3475);
DISPLAY INVISIBLE (-5852 3475);
FORCEADD TAP..1
(-5850 3575);
FORCEPROP 3 LASTPIN (-5900 3575) SIG_NAME M_J_CPU1_SB_DQ<29>
J 0
(-5890 3585);
DISPLAY 0.659574 (-5890 3585);
PAINT MONO (-5890 3585);
DISPLAY INVISIBLE (-5890 3585);
FORCEPROP 1 LASTPIN (-5900 3575) BN 29
J 0
(-5912 3583);
DISPLAY 0.489362 (-5912 3583);
PAINT GREEN (-5912 3583);
FORCEPROP 2 LAST CDS_LIB mstr_standard
J 0
(-5850 3575);
DISPLAY 0.723404 (-5850 3575);
PAINT MONO (-5850 3575);
DISPLAY INVISIBLE (-5850 3575);
FORCEPROP 1 LAST BODY_TYPE PLUMBING
J 0
(-5850 3625);
DISPLAY 0.872340 (-5850 3625);
PAINT GREEN (-5850 3625);
DISPLAY INVISIBLE (-5850 3625);
FORCEPROP 1 LAST HDL_TAP TRUE
J 0
(-5525 3450);
DISPLAY 0.872340 (-5525 3450);
DISPLAY INVISIBLE (-5525 3450);
FORCEPROP 1 LAST PATH I65
J 0
(-5852 3575);
DISPLAY 0.872340 (-5852 3575);
PAINT GREEN (-5852 3575);
DISPLAY INVISIBLE (-5852 3575);
FORCEADD TAP..1
(-5850 3525);
FORCEPROP 3 LASTPIN (-5900 3525) SIG_NAME M_J_CPU1_SB_DQ<28>
J 0
(-5890 3535);
DISPLAY 0.659574 (-5890 3535);
PAINT MONO (-5890 3535);
DISPLAY INVISIBLE (-5890 3535);
FORCEPROP 1 LASTPIN (-5900 3525) BN 28
J 0
(-5912 3533);
DISPLAY 0.489362 (-5912 3533);
PAINT GREEN (-5912 3533);
FORCEPROP 2 LAST CDS_LIB mstr_standard
J 0
(-5850 3525);
DISPLAY 0.723404 (-5850 3525);
PAINT MONO (-5850 3525);
DISPLAY INVISIBLE (-5850 3525);
FORCEPROP 1 LAST BODY_TYPE PLUMBING
J 0
(-5850 3575);
DISPLAY 0.872340 (-5850 3575);
PAINT GREEN (-5850 3575);
DISPLAY INVISIBLE (-5850 3575);
FORCEPROP 1 LAST HDL_TAP TRUE
J 0
(-5525 3400);
DISPLAY 0.872340 (-5525 3400);
DISPLAY INVISIBLE (-5525 3400);
FORCEPROP 1 LAST PATH I66
J 0
(-5852 3525);
DISPLAY 0.872340 (-5852 3525);
PAINT GREEN (-5852 3525);
DISPLAY INVISIBLE (-5852 3525);
FORCEADD TAP..1
(-5850 3675);
FORCEPROP 3 LASTPIN (-5900 3675) SIG_NAME M_J_CPU1_SB_DQ<31>
J 0
(-5890 3685);
DISPLAY 0.659574 (-5890 3685);
PAINT MONO (-5890 3685);
DISPLAY INVISIBLE (-5890 3685);
FORCEPROP 1 LASTPIN (-5900 3675) BN 31
J 0
(-5912 3683);
DISPLAY 0.489362 (-5912 3683);
PAINT GREEN (-5912 3683);
FORCEPROP 2 LAST CDS_LIB mstr_standard
J 0
(-5850 3675);
DISPLAY 0.723404 (-5850 3675);
PAINT MONO (-5850 3675);
DISPLAY INVISIBLE (-5850 3675);
FORCEPROP 1 LAST BODY_TYPE PLUMBING
J 0
(-5850 3725);
DISPLAY 0.872340 (-5850 3725);
PAINT GREEN (-5850 3725);
DISPLAY INVISIBLE (-5850 3725);
FORCEPROP 1 LAST HDL_TAP TRUE
J 0
(-5525 3550);
DISPLAY 0.872340 (-5525 3550);
DISPLAY INVISIBLE (-5525 3550);
FORCEPROP 1 LAST PATH I67
J 0
(-5852 3675);
DISPLAY 0.872340 (-5852 3675);
PAINT GREEN (-5852 3675);
DISPLAY INVISIBLE (-5852 3675);
FORCEADD TAP..1
(-5850 3625);
FORCEPROP 3 LASTPIN (-5900 3625) SIG_NAME M_J_CPU1_SB_DQ<30>
J 0
(-5890 3635);
DISPLAY 0.659574 (-5890 3635);
PAINT MONO (-5890 3635);
DISPLAY INVISIBLE (-5890 3635);
FORCEPROP 1 LASTPIN (-5900 3625) BN 30
J 0
(-5912 3633);
DISPLAY 0.489362 (-5912 3633);
PAINT GREEN (-5912 3633);
FORCEPROP 2 LAST CDS_LIB mstr_standard
J 0
(-5850 3625);
DISPLAY 0.723404 (-5850 3625);
PAINT MONO (-5850 3625);
DISPLAY INVISIBLE (-5850 3625);
FORCEPROP 1 LAST BODY_TYPE PLUMBING
J 0
(-5850 3675);
DISPLAY 0.872340 (-5850 3675);
PAINT GREEN (-5850 3675);
DISPLAY INVISIBLE (-5850 3675);
FORCEPROP 1 LAST HDL_TAP TRUE
J 0
(-5525 3500);
DISPLAY 0.872340 (-5525 3500);
DISPLAY INVISIBLE (-5525 3500);
FORCEPROP 1 LAST PATH I68
J 0
(-5852 3625);
DISPLAY 0.872340 (-5852 3625);
PAINT GREEN (-5852 3625);
DISPLAY INVISIBLE (-5852 3625);
FORCEADD TAP..1
(-5850 3775);
FORCEPROP 3 LASTPIN (-5900 3775) SIG_NAME M_J_CPU1_SA_DQ<0>
J 0
(-5890 3785);
DISPLAY 0.659574 (-5890 3785);
PAINT MONO (-5890 3785);
DISPLAY INVISIBLE (-5890 3785);
FORCEPROP 1 LASTPIN (-5900 3775) BN 0
J 0
(-5912 3783);
DISPLAY 0.489362 (-5912 3783);
PAINT GREEN (-5912 3783);
FORCEPROP 2 LAST CDS_LIB mstr_standard
J 0
(-5850 3775);
DISPLAY 0.723404 (-5850 3775);
PAINT MONO (-5850 3775);
DISPLAY INVISIBLE (-5850 3775);
FORCEPROP 1 LAST BODY_TYPE PLUMBING
J 0
(-5850 3825);
DISPLAY 0.872340 (-5850 3825);
PAINT GREEN (-5850 3825);
DISPLAY INVISIBLE (-5850 3825);
FORCEPROP 1 LAST HDL_TAP TRUE
J 0
(-5525 3650);
DISPLAY 0.872340 (-5525 3650);
DISPLAY INVISIBLE (-5525 3650);
FORCEPROP 1 LAST PATH I69
J 0
(-5852 3775);
DISPLAY 0.872340 (-5852 3775);
PAINT GREEN (-5852 3775);
DISPLAY INVISIBLE (-5852 3775);
FORCEADD VCC_CORE..1
(-8425 3350);
FORCEPROP 3 LASTPIN (-8425 3300) SIG_NAME P3V3_AUX\g
J 0
(-8415 3310);
DISPLAY 0.659574 (-8415 3310);
PAINT MONO (-8415 3310);
DISPLAY INVISIBLE (-8415 3310);
FORCEPROP 1 LAST HDL_POWER P3V3_AUX
J 1
(-8425 3400);
DISPLAY 0.489362 (-8425 3400);
PAINT GREEN (-8425 3400);
FORCEPROP 2 LAST ROOM PVCCINFAON_CPU1_CTRL
J 0
(-8425 3450);
DISPLAY 0.808511 (-8425 3450);
PAINT RED (-8425 3450);
DISPLAY INVISIBLE (-8425 3450);
FORCEPROP 0 LAST VOLTAGE 3.3
J 0
(-8700 3500);
DISPLAY 1.021277 (-8700 3500);
PAINT SKYBLUE (-8700 3500);
DISPLAY INVISIBLE (-8700 3500);
FORCEPROP 2 LAST CDS_LIB mstr_symbols
J 0
(-8425 3350);
PAINT MONO (-8425 3350);
DISPLAY INVISIBLE (-8425 3350);
FORCEPROP 1 LAST PATH I7
J 0
(-8375 3375);
DISPLAY 0.872340 (-8375 3375);
PAINT AQUA (-8375 3375);
DISPLAY INVISIBLE (-8375 3375);
FORCEADD TAP..1
(-5850 3825);
FORCEPROP 3 LASTPIN (-5900 3825) SIG_NAME M_J_CPU1_SA_DQ<1>
J 0
(-5890 3835);
DISPLAY 0.659574 (-5890 3835);
PAINT MONO (-5890 3835);
DISPLAY INVISIBLE (-5890 3835);
FORCEPROP 1 LASTPIN (-5900 3825) BN 1
J 0
(-5912 3833);
DISPLAY 0.489362 (-5912 3833);
PAINT GREEN (-5912 3833);
FORCEPROP 2 LAST CDS_LIB mstr_standard
J 0
(-5850 3825);
DISPLAY 0.723404 (-5850 3825);
PAINT MONO (-5850 3825);
DISPLAY INVISIBLE (-5850 3825);
FORCEPROP 1 LAST BODY_TYPE PLUMBING
J 0
(-5850 3875);
DISPLAY 0.872340 (-5850 3875);
PAINT GREEN (-5850 3875);
DISPLAY INVISIBLE (-5850 3875);
FORCEPROP 1 LAST HDL_TAP TRUE
J 0
(-5525 3700);
DISPLAY 0.872340 (-5525 3700);
DISPLAY INVISIBLE (-5525 3700);
FORCEPROP 1 LAST PATH I70
J 0
(-5852 3825);
DISPLAY 0.872340 (-5852 3825);
PAINT GREEN (-5852 3825);
DISPLAY INVISIBLE (-5852 3825);
FORCEADD OFFPAGE..3
(-5200 3725);
FORCEPROP 2 LAST $XR0 46 
J 0
(-4986 3725);
DISPLAY 0.638298 (-4986 3725);
PAINT MONO (-4986 3725);
FORCEPROP 2 LAST CDS_LIB mstr_standard
J 0
(-5200 3725);
DISPLAY 0.723404 (-5200 3725);
PAINT MONO (-5200 3725);
DISPLAY INVISIBLE (-5200 3725);
FORCEPROP 1 LAST OFFPAGE TRUE
J 0
(-4875 3600);
DISPLAY 0.872340 (-4875 3600);
PAINT GREEN (-4875 3600);
DISPLAY INVISIBLE (-4875 3600);
FORCEPROP 1 LAST COMMENT_BODY TRUE
J 0
(-5250 3625);
DISPLAY 0.872340 (-5250 3625);
PAINT GREEN (-5250 3625);
DISPLAY INVISIBLE (-5250 3625);
FORCEPROP 2 LAST PATH I78
J 0
(-4975 3775);
DISPLAY 1.021277 (-4975 3775);
DISPLAY INVISIBLE (-4975 3775);
FORCEADD TAP..1
R 2
(-7550 3875);
FORCEPROP 3 LASTPIN (-7500 3875) SIG_NAME M_J_CPU1_SA_CB<6>
J 0
(-7490 3885);
DISPLAY 0.659574 (-7490 3885);
PAINT MONO (-7490 3885);
DISPLAY INVISIBLE (-7490 3885);
FORCEPROP 1 LASTPIN (-7500 3875) BN 6
J 2
(-7488 3883);
DISPLAY 0.489362 (-7488 3883);
PAINT GREEN (-7488 3883);
FORCEPROP 2 LAST CDS_LIB mstr_standard
J 0
(-7550 3875);
DISPLAY 0.723404 (-7550 3875);
PAINT MONO (-7550 3875);
DISPLAY INVISIBLE (-7550 3875);
FORCEPROP 1 LAST BODY_TYPE PLUMBING
J 2
(-7550 3925);
DISPLAY 0.872340 (-7550 3925);
PAINT GREEN (-7550 3925);
DISPLAY INVISIBLE (-7550 3925);
FORCEPROP 1 LAST HDL_TAP TRUE
J 2
(-7875 3750);
DISPLAY 0.872340 (-7875 3750);
DISPLAY INVISIBLE (-7875 3750);
FORCEPROP 1 LAST PATH I79
J 2
(-7548 3875);
DISPLAY 0.872340 (-7548 3875);
PAINT GREEN (-7548 3875);
DISPLAY INVISIBLE (-7548 3875);
FORCEADD OFFPAGE..1
(-7950 3025);
FORCEPROP 2 LAST $XR0 46 
J 0
(-8171 3025);
DISPLAY 0.638298 (-8171 3025);
PAINT MONO (-8171 3025);
FORCEPROP 2 LAST CDS_LIB mstr_standard
J 0
(-7950 3025);
DISPLAY 0.808511 (-7950 3025);
DISPLAY INVISIBLE (-7950 3025);
FORCEPROP 1 LAST OFFPAGE TRUE
J 0
(-7625 2900);
DISPLAY 0.872340 (-7625 2900);
PAINT GREEN (-7625 2900);
DISPLAY INVISIBLE (-7625 2900);
FORCEPROP 1 LAST COMMENT_BODY TRUE
J 0
(-7825 2925);
DISPLAY 0.872340 (-7825 2925);
PAINT GREEN (-7825 2925);
DISPLAY INVISIBLE (-7825 2925);
FORCEPROP 2 LAST PATH I8
J 0
(-8150 3075);
DISPLAY 1.021277 (-8150 3075);
DISPLAY INVISIBLE (-8150 3075);
FORCEADD TAP..1
R 2
(-7550 3925);
FORCEPROP 3 LASTPIN (-7500 3925) SIG_NAME M_J_CPU1_SA_CB<7>
J 0
(-7490 3935);
DISPLAY 0.659574 (-7490 3935);
PAINT MONO (-7490 3935);
DISPLAY INVISIBLE (-7490 3935);
FORCEPROP 1 LASTPIN (-7500 3925) BN 7
J 2
(-7488 3933);
DISPLAY 0.489362 (-7488 3933);
PAINT GREEN (-7488 3933);
FORCEPROP 2 LAST CDS_LIB mstr_standard
J 0
(-7550 3925);
DISPLAY 0.723404 (-7550 3925);
PAINT MONO (-7550 3925);
DISPLAY INVISIBLE (-7550 3925);
FORCEPROP 1 LAST BODY_TYPE PLUMBING
J 2
(-7550 3975);
DISPLAY 0.872340 (-7550 3975);
PAINT GREEN (-7550 3975);
DISPLAY INVISIBLE (-7550 3975);
FORCEPROP 1 LAST HDL_TAP TRUE
J 2
(-7875 3800);
DISPLAY 0.872340 (-7875 3800);
DISPLAY INVISIBLE (-7875 3800);
FORCEPROP 1 LAST PATH I80
J 2
(-7548 3925);
DISPLAY 0.872340 (-7548 3925);
PAINT GREEN (-7548 3925);
DISPLAY INVISIBLE (-7548 3925);
FORCEADD TAP..1
R 2
(-7550 4625);
FORCEPROP 3 LASTPIN (-7500 4625) SIG_NAME M_J_CPU1_SB_CA<0>
J 0
(-7490 4635);
DISPLAY 0.659574 (-7490 4635);
PAINT MONO (-7490 4635);
DISPLAY INVISIBLE (-7490 4635);
FORCEPROP 1 LASTPIN (-7500 4625) BN 0
J 2
(-7488 4633);
DISPLAY 0.489362 (-7488 4633);
PAINT GREEN (-7488 4633);
FORCEPROP 2 LAST CDS_LIB mstr_standard
J 0
(-7550 4625);
DISPLAY 0.723404 (-7550 4625);
PAINT MONO (-7550 4625);
DISPLAY INVISIBLE (-7550 4625);
FORCEPROP 1 LAST BODY_TYPE PLUMBING
J 2
(-7550 4675);
DISPLAY 0.872340 (-7550 4675);
PAINT GREEN (-7550 4675);
DISPLAY INVISIBLE (-7550 4675);
FORCEPROP 1 LAST HDL_TAP TRUE
J 2
(-7875 4500);
DISPLAY 0.872340 (-7875 4500);
DISPLAY INVISIBLE (-7875 4500);
FORCEPROP 1 LAST PATH I81
J 2
(-7548 4625);
DISPLAY 0.872340 (-7548 4625);
PAINT GREEN (-7548 4625);
DISPLAY INVISIBLE (-7548 4625);
FORCEADD TAP..1
R 2
(-7550 4725);
FORCEPROP 3 LASTPIN (-7500 4725) SIG_NAME M_J_CPU1_SB_CA<2>
J 0
(-7490 4735);
DISPLAY 0.659574 (-7490 4735);
PAINT MONO (-7490 4735);
DISPLAY INVISIBLE (-7490 4735);
FORCEPROP 1 LASTPIN (-7500 4725) BN 2
J 2
(-7488 4733);
DISPLAY 0.489362 (-7488 4733);
PAINT GREEN (-7488 4733);
FORCEPROP 2 LAST CDS_LIB mstr_standard
J 0
(-7550 4725);
DISPLAY 0.723404 (-7550 4725);
PAINT MONO (-7550 4725);
DISPLAY INVISIBLE (-7550 4725);
FORCEPROP 1 LAST BODY_TYPE PLUMBING
J 2
(-7550 4775);
DISPLAY 0.872340 (-7550 4775);
PAINT GREEN (-7550 4775);
DISPLAY INVISIBLE (-7550 4775);
FORCEPROP 1 LAST HDL_TAP TRUE
J 2
(-7875 4600);
DISPLAY 0.872340 (-7875 4600);
DISPLAY INVISIBLE (-7875 4600);
FORCEPROP 1 LAST PATH I82
J 2
(-7548 4725);
DISPLAY 0.872340 (-7548 4725);
PAINT GREEN (-7548 4725);
DISPLAY INVISIBLE (-7548 4725);
FORCEADD TAP..1
R 2
(-7550 4675);
FORCEPROP 3 LASTPIN (-7500 4675) SIG_NAME M_J_CPU1_SB_CA<1>
J 0
(-7490 4685);
DISPLAY 0.659574 (-7490 4685);
PAINT MONO (-7490 4685);
DISPLAY INVISIBLE (-7490 4685);
FORCEPROP 1 LASTPIN (-7500 4675) BN 1
J 2
(-7488 4683);
DISPLAY 0.489362 (-7488 4683);
PAINT GREEN (-7488 4683);
FORCEPROP 2 LAST CDS_LIB mstr_standard
J 0
(-7550 4675);
DISPLAY 0.723404 (-7550 4675);
PAINT MONO (-7550 4675);
DISPLAY INVISIBLE (-7550 4675);
FORCEPROP 1 LAST BODY_TYPE PLUMBING
J 2
(-7550 4725);
DISPLAY 0.872340 (-7550 4725);
PAINT GREEN (-7550 4725);
DISPLAY INVISIBLE (-7550 4725);
FORCEPROP 1 LAST HDL_TAP TRUE
J 2
(-7875 4550);
DISPLAY 0.872340 (-7875 4550);
DISPLAY INVISIBLE (-7875 4550);
FORCEPROP 1 LAST PATH I83
J 2
(-7548 4675);
DISPLAY 0.872340 (-7548 4675);
PAINT GREEN (-7548 4675);
DISPLAY INVISIBLE (-7548 4675);
FORCEADD TAP..1
R 2
(-7550 4825);
FORCEPROP 3 LASTPIN (-7500 4825) SIG_NAME M_J_CPU1_SB_CA<4>
J 0
(-7490 4835);
DISPLAY 0.659574 (-7490 4835);
PAINT MONO (-7490 4835);
DISPLAY INVISIBLE (-7490 4835);
FORCEPROP 1 LASTPIN (-7500 4825) BN 4
J 2
(-7488 4833);
DISPLAY 0.489362 (-7488 4833);
PAINT GREEN (-7488 4833);
FORCEPROP 2 LAST CDS_LIB mstr_standard
J 0
(-7550 4825);
DISPLAY 0.723404 (-7550 4825);
PAINT MONO (-7550 4825);
DISPLAY INVISIBLE (-7550 4825);
FORCEPROP 1 LAST BODY_TYPE PLUMBING
J 2
(-7550 4875);
DISPLAY 0.872340 (-7550 4875);
PAINT GREEN (-7550 4875);
DISPLAY INVISIBLE (-7550 4875);
FORCEPROP 1 LAST HDL_TAP TRUE
J 2
(-7875 4700);
DISPLAY 0.872340 (-7875 4700);
DISPLAY INVISIBLE (-7875 4700);
FORCEPROP 1 LAST PATH I84
J 2
(-7548 4825);
DISPLAY 0.872340 (-7548 4825);
PAINT GREEN (-7548 4825);
DISPLAY INVISIBLE (-7548 4825);
FORCEADD TAP..1
R 2
(-7550 4775);
FORCEPROP 3 LASTPIN (-7500 4775) SIG_NAME M_J_CPU1_SB_CA<3>
J 0
(-7490 4785);
DISPLAY 0.659574 (-7490 4785);
PAINT MONO (-7490 4785);
DISPLAY INVISIBLE (-7490 4785);
FORCEPROP 1 LASTPIN (-7500 4775) BN 3
J 2
(-7488 4783);
DISPLAY 0.489362 (-7488 4783);
PAINT GREEN (-7488 4783);
FORCEPROP 2 LAST CDS_LIB mstr_standard
J 0
(-7550 4775);
DISPLAY 0.723404 (-7550 4775);
PAINT MONO (-7550 4775);
DISPLAY INVISIBLE (-7550 4775);
FORCEPROP 1 LAST BODY_TYPE PLUMBING
J 2
(-7550 4825);
DISPLAY 0.872340 (-7550 4825);
PAINT GREEN (-7550 4825);
DISPLAY INVISIBLE (-7550 4825);
FORCEPROP 1 LAST HDL_TAP TRUE
J 2
(-7875 4650);
DISPLAY 0.872340 (-7875 4650);
DISPLAY INVISIBLE (-7875 4650);
FORCEPROP 1 LAST PATH I85
J 2
(-7548 4775);
DISPLAY 0.872340 (-7548 4775);
PAINT GREEN (-7548 4775);
DISPLAY INVISIBLE (-7548 4775);
FORCEADD TAP..1
R 2
(-7550 4875);
FORCEPROP 3 LASTPIN (-7500 4875) SIG_NAME M_J_CPU1_SB_CA<5>
J 0
(-7490 4885);
DISPLAY 0.659574 (-7490 4885);
PAINT MONO (-7490 4885);
DISPLAY INVISIBLE (-7490 4885);
FORCEPROP 1 LASTPIN (-7500 4875) BN 5
J 2
(-7488 4883);
DISPLAY 0.489362 (-7488 4883);
PAINT GREEN (-7488 4883);
FORCEPROP 2 LAST CDS_LIB mstr_standard
J 0
(-7550 4875);
DISPLAY 0.723404 (-7550 4875);
PAINT MONO (-7550 4875);
DISPLAY INVISIBLE (-7550 4875);
FORCEPROP 1 LAST BODY_TYPE PLUMBING
J 2
(-7550 4925);
DISPLAY 0.872340 (-7550 4925);
PAINT GREEN (-7550 4925);
DISPLAY INVISIBLE (-7550 4925);
FORCEPROP 1 LAST HDL_TAP TRUE
J 2
(-7875 4750);
DISPLAY 0.872340 (-7875 4750);
DISPLAY INVISIBLE (-7875 4750);
FORCEPROP 1 LAST PATH I86
J 2
(-7548 4875);
DISPLAY 0.872340 (-7548 4875);
PAINT GREEN (-7548 4875);
DISPLAY INVISIBLE (-7548 4875);
FORCEADD TAP..1
R 2
(-7550 4925);
FORCEPROP 3 LASTPIN (-7500 4925) SIG_NAME M_J_CPU1_SB_CA<6>
J 0
(-7490 4935);
DISPLAY 0.659574 (-7490 4935);
PAINT MONO (-7490 4935);
DISPLAY INVISIBLE (-7490 4935);
FORCEPROP 1 LASTPIN (-7500 4925) BN 6
J 2
(-7488 4933);
DISPLAY 0.489362 (-7488 4933);
PAINT GREEN (-7488 4933);
FORCEPROP 2 LAST CDS_LIB mstr_standard
J 0
(-7550 4925);
DISPLAY 0.723404 (-7550 4925);
PAINT MONO (-7550 4925);
DISPLAY INVISIBLE (-7550 4925);
FORCEPROP 1 LAST BODY_TYPE PLUMBING
J 2
(-7550 4975);
DISPLAY 0.872340 (-7550 4975);
PAINT GREEN (-7550 4975);
DISPLAY INVISIBLE (-7550 4975);
FORCEPROP 1 LAST HDL_TAP TRUE
J 2
(-7875 4800);
DISPLAY 0.872340 (-7875 4800);
DISPLAY INVISIBLE (-7875 4800);
FORCEPROP 1 LAST PATH I87
J 2
(-7548 4925);
DISPLAY 0.872340 (-7548 4925);
PAINT GREEN (-7548 4925);
DISPLAY INVISIBLE (-7548 4925);
FORCEADD TAP..1
R 2
(-7550 5025);
FORCEPROP 3 LASTPIN (-7500 5025) SIG_NAME M_J_CPU1_SA_CA<0>
J 0
(-7490 5035);
DISPLAY 0.659574 (-7490 5035);
PAINT MONO (-7490 5035);
DISPLAY INVISIBLE (-7490 5035);
FORCEPROP 1 LASTPIN (-7500 5025) BN 0
J 2
(-7488 5033);
DISPLAY 0.489362 (-7488 5033);
PAINT GREEN (-7488 5033);
FORCEPROP 2 LAST CDS_LIB mstr_standard
J 0
(-7550 5025);
DISPLAY 0.723404 (-7550 5025);
PAINT MONO (-7550 5025);
DISPLAY INVISIBLE (-7550 5025);
FORCEPROP 1 LAST BODY_TYPE PLUMBING
J 2
(-7550 5075);
DISPLAY 0.872340 (-7550 5075);
PAINT GREEN (-7550 5075);
DISPLAY INVISIBLE (-7550 5075);
FORCEPROP 1 LAST HDL_TAP TRUE
J 2
(-7875 4900);
DISPLAY 0.872340 (-7875 4900);
DISPLAY INVISIBLE (-7875 4900);
FORCEPROP 1 LAST PATH I88
J 2
(-7548 5025);
DISPLAY 0.872340 (-7548 5025);
PAINT GREEN (-7548 5025);
DISPLAY INVISIBLE (-7548 5025);
FORCEADD TAP..1
R 2
(-7550 5075);
FORCEPROP 3 LASTPIN (-7500 5075) SIG_NAME M_J_CPU1_SA_CA<1>
J 0
(-7490 5085);
DISPLAY 0.659574 (-7490 5085);
PAINT MONO (-7490 5085);
DISPLAY INVISIBLE (-7490 5085);
FORCEPROP 1 LASTPIN (-7500 5075) BN 1
J 2
(-7488 5083);
DISPLAY 0.489362 (-7488 5083);
PAINT GREEN (-7488 5083);
FORCEPROP 2 LAST CDS_LIB mstr_standard
J 0
(-7550 5075);
DISPLAY 0.723404 (-7550 5075);
PAINT MONO (-7550 5075);
DISPLAY INVISIBLE (-7550 5075);
FORCEPROP 1 LAST BODY_TYPE PLUMBING
J 2
(-7550 5125);
DISPLAY 0.872340 (-7550 5125);
PAINT GREEN (-7550 5125);
DISPLAY INVISIBLE (-7550 5125);
FORCEPROP 1 LAST HDL_TAP TRUE
J 2
(-7875 4950);
DISPLAY 0.872340 (-7875 4950);
DISPLAY INVISIBLE (-7875 4950);
FORCEPROP 1 LAST PATH I89
J 2
(-7548 5075);
DISPLAY 0.872340 (-7548 5075);
PAINT GREEN (-7548 5075);
DISPLAY INVISIBLE (-7548 5075);
FORCEADD OFFPAGE..5
(-7950 2975);
FORCEPROP 2 LAST $XR0 46 
J 0
(-8204 2975);
DISPLAY 0.638298 (-8204 2975);
PAINT MONO (-8204 2975);
FORCEPROP 2 LAST CDS_LIB mstr_standard
J 0
(-7950 2975);
DISPLAY INVISIBLE (-7950 2975);
FORCEPROP 1 LAST OFFPAGE TRUE
J 0
(-7625 2850);
DISPLAY 0.872340 (-7625 2850);
PAINT GREEN (-7625 2850);
DISPLAY INVISIBLE (-7625 2850);
FORCEPROP 1 LAST COMMENT_BODY TRUE
J 0
(-7850 2900);
DISPLAY 0.872340 (-7850 2900);
PAINT GREEN (-7850 2900);
DISPLAY INVISIBLE (-7850 2900);
FORCEPROP 2 LAST PATH I9
J 0
(-8200 3025);
DISPLAY 1.021277 (-8200 3025);
DISPLAY INVISIBLE (-8200 3025);
FORCEADD TAP..1
R 2
(-7550 5125);
FORCEPROP 3 LASTPIN (-7500 5125) SIG_NAME M_J_CPU1_SA_CA<2>
J 0
(-7490 5135);
DISPLAY 0.659574 (-7490 5135);
PAINT MONO (-7490 5135);
DISPLAY INVISIBLE (-7490 5135);
FORCEPROP 1 LASTPIN (-7500 5125) BN 2
J 2
(-7488 5133);
DISPLAY 0.489362 (-7488 5133);
PAINT GREEN (-7488 5133);
FORCEPROP 2 LAST CDS_LIB mstr_standard
J 0
(-7550 5125);
DISPLAY 0.723404 (-7550 5125);
PAINT MONO (-7550 5125);
DISPLAY INVISIBLE (-7550 5125);
FORCEPROP 1 LAST BODY_TYPE PLUMBING
J 2
(-7550 5175);
DISPLAY 0.872340 (-7550 5175);
PAINT GREEN (-7550 5175);
DISPLAY INVISIBLE (-7550 5175);
FORCEPROP 1 LAST HDL_TAP TRUE
J 2
(-7875 5000);
DISPLAY 0.872340 (-7875 5000);
DISPLAY INVISIBLE (-7875 5000);
FORCEPROP 1 LAST PATH I90
J 2
(-7548 5125);
DISPLAY 0.872340 (-7548 5125);
PAINT GREEN (-7548 5125);
DISPLAY INVISIBLE (-7548 5125);
FORCEADD TAP..1
R 2
(-7550 5175);
FORCEPROP 3 LASTPIN (-7500 5175) SIG_NAME M_J_CPU1_SA_CA<3>
J 0
(-7490 5185);
DISPLAY 0.659574 (-7490 5185);
PAINT MONO (-7490 5185);
DISPLAY INVISIBLE (-7490 5185);
FORCEPROP 1 LASTPIN (-7500 5175) BN 3
J 2
(-7488 5183);
DISPLAY 0.489362 (-7488 5183);
PAINT GREEN (-7488 5183);
FORCEPROP 2 LAST CDS_LIB mstr_standard
J 0
(-7550 5175);
DISPLAY 0.723404 (-7550 5175);
PAINT MONO (-7550 5175);
DISPLAY INVISIBLE (-7550 5175);
FORCEPROP 1 LAST BODY_TYPE PLUMBING
J 2
(-7550 5225);
DISPLAY 0.872340 (-7550 5225);
PAINT GREEN (-7550 5225);
DISPLAY INVISIBLE (-7550 5225);
FORCEPROP 1 LAST HDL_TAP TRUE
J 2
(-7875 5050);
DISPLAY 0.872340 (-7875 5050);
DISPLAY INVISIBLE (-7875 5050);
FORCEPROP 1 LAST PATH I91
J 2
(-7548 5175);
DISPLAY 0.872340 (-7548 5175);
PAINT GREEN (-7548 5175);
DISPLAY INVISIBLE (-7548 5175);
FORCEADD TAP..1
R 2
(-7550 5225);
FORCEPROP 3 LASTPIN (-7500 5225) SIG_NAME M_J_CPU1_SA_CA<4>
J 0
(-7490 5235);
DISPLAY 0.659574 (-7490 5235);
PAINT MONO (-7490 5235);
DISPLAY INVISIBLE (-7490 5235);
FORCEPROP 1 LASTPIN (-7500 5225) BN 4
J 2
(-7488 5233);
DISPLAY 0.489362 (-7488 5233);
PAINT GREEN (-7488 5233);
FORCEPROP 2 LAST CDS_LIB mstr_standard
J 0
(-7550 5225);
DISPLAY 0.723404 (-7550 5225);
PAINT MONO (-7550 5225);
DISPLAY INVISIBLE (-7550 5225);
FORCEPROP 1 LAST BODY_TYPE PLUMBING
J 2
(-7550 5275);
DISPLAY 0.872340 (-7550 5275);
PAINT GREEN (-7550 5275);
DISPLAY INVISIBLE (-7550 5275);
FORCEPROP 1 LAST HDL_TAP TRUE
J 2
(-7875 5100);
DISPLAY 0.872340 (-7875 5100);
DISPLAY INVISIBLE (-7875 5100);
FORCEPROP 1 LAST PATH I92
J 2
(-7548 5225);
DISPLAY 0.872340 (-7548 5225);
PAINT GREEN (-7548 5225);
DISPLAY INVISIBLE (-7548 5225);
FORCEADD TAP..1
R 2
(-7550 5275);
FORCEPROP 3 LASTPIN (-7500 5275) SIG_NAME M_J_CPU1_SA_CA<5>
J 0
(-7490 5285);
DISPLAY 0.659574 (-7490 5285);
PAINT MONO (-7490 5285);
DISPLAY INVISIBLE (-7490 5285);
FORCEPROP 1 LASTPIN (-7500 5275) BN 5
J 2
(-7488 5283);
DISPLAY 0.489362 (-7488 5283);
PAINT GREEN (-7488 5283);
FORCEPROP 2 LAST CDS_LIB mstr_standard
J 0
(-7550 5275);
DISPLAY 0.723404 (-7550 5275);
PAINT MONO (-7550 5275);
DISPLAY INVISIBLE (-7550 5275);
FORCEPROP 1 LAST BODY_TYPE PLUMBING
J 2
(-7550 5325);
DISPLAY 0.872340 (-7550 5325);
PAINT GREEN (-7550 5325);
DISPLAY INVISIBLE (-7550 5325);
FORCEPROP 1 LAST HDL_TAP TRUE
J 2
(-7875 5150);
DISPLAY 0.872340 (-7875 5150);
DISPLAY INVISIBLE (-7875 5150);
FORCEPROP 1 LAST PATH I93
J 2
(-7548 5275);
DISPLAY 0.872340 (-7548 5275);
PAINT GREEN (-7548 5275);
DISPLAY INVISIBLE (-7548 5275);
FORCEADD TAP..1
R 2
(-7550 5325);
FORCEPROP 3 LASTPIN (-7500 5325) SIG_NAME M_J_CPU1_SA_CA<6>
J 0
(-7490 5335);
DISPLAY 0.659574 (-7490 5335);
PAINT MONO (-7490 5335);
DISPLAY INVISIBLE (-7490 5335);
FORCEPROP 1 LASTPIN (-7500 5325) BN 6
J 2
(-7488 5333);
DISPLAY 0.489362 (-7488 5333);
PAINT GREEN (-7488 5333);
FORCEPROP 2 LAST CDS_LIB mstr_standard
J 0
(-7550 5325);
DISPLAY 0.723404 (-7550 5325);
PAINT MONO (-7550 5325);
DISPLAY INVISIBLE (-7550 5325);
FORCEPROP 1 LAST BODY_TYPE PLUMBING
J 2
(-7550 5375);
DISPLAY 0.872340 (-7550 5375);
PAINT GREEN (-7550 5375);
DISPLAY INVISIBLE (-7550 5375);
FORCEPROP 1 LAST HDL_TAP TRUE
J 2
(-7875 5200);
DISPLAY 0.872340 (-7875 5200);
DISPLAY INVISIBLE (-7875 5200);
FORCEPROP 1 LAST PATH I94
J 2
(-7548 5325);
DISPLAY 0.872340 (-7548 5325);
PAINT GREEN (-7548 5325);
DISPLAY INVISIBLE (-7548 5325);
FORCEADD TAP..1
(-5850 3875);
FORCEPROP 3 LASTPIN (-5900 3875) SIG_NAME M_J_CPU1_SA_DQ<2>
J 0
(-5890 3885);
DISPLAY 0.659574 (-5890 3885);
PAINT MONO (-5890 3885);
DISPLAY INVISIBLE (-5890 3885);
FORCEPROP 1 LASTPIN (-5900 3875) BN 2
J 0
(-5912 3883);
DISPLAY 0.489362 (-5912 3883);
PAINT GREEN (-5912 3883);
FORCEPROP 2 LAST CDS_LIB mstr_standard
J 0
(-5850 3875);
DISPLAY 0.723404 (-5850 3875);
PAINT MONO (-5850 3875);
DISPLAY INVISIBLE (-5850 3875);
FORCEPROP 1 LAST BODY_TYPE PLUMBING
J 0
(-5850 3925);
DISPLAY 0.872340 (-5850 3925);
PAINT GREEN (-5850 3925);
DISPLAY INVISIBLE (-5850 3925);
FORCEPROP 1 LAST HDL_TAP TRUE
J 0
(-5525 3750);
DISPLAY 0.872340 (-5525 3750);
DISPLAY INVISIBLE (-5525 3750);
FORCEPROP 1 LAST PATH I95
J 0
(-5852 3875);
DISPLAY 0.872340 (-5852 3875);
PAINT GREEN (-5852 3875);
DISPLAY INVISIBLE (-5852 3875);
FORCEADD TAP..1
(-5850 3925);
FORCEPROP 3 LASTPIN (-5900 3925) SIG_NAME M_J_CPU1_SA_DQ<3>
J 0
(-5890 3935);
DISPLAY 0.659574 (-5890 3935);
PAINT MONO (-5890 3935);
DISPLAY INVISIBLE (-5890 3935);
FORCEPROP 1 LASTPIN (-5900 3925) BN 3
J 0
(-5912 3933);
DISPLAY 0.489362 (-5912 3933);
PAINT GREEN (-5912 3933);
FORCEPROP 2 LAST CDS_LIB mstr_standard
J 0
(-5850 3925);
DISPLAY 0.723404 (-5850 3925);
PAINT MONO (-5850 3925);
DISPLAY INVISIBLE (-5850 3925);
FORCEPROP 1 LAST BODY_TYPE PLUMBING
J 0
(-5850 3975);
DISPLAY 0.872340 (-5850 3975);
PAINT GREEN (-5850 3975);
DISPLAY INVISIBLE (-5850 3975);
FORCEPROP 1 LAST HDL_TAP TRUE
J 0
(-5525 3800);
DISPLAY 0.872340 (-5525 3800);
DISPLAY INVISIBLE (-5525 3800);
FORCEPROP 1 LAST PATH I96
J 0
(-5852 3925);
DISPLAY 0.872340 (-5852 3925);
PAINT GREEN (-5852 3925);
DISPLAY INVISIBLE (-5852 3925);
FORCEADD TAP..1
(-5850 3975);
FORCEPROP 3 LASTPIN (-5900 3975) SIG_NAME M_J_CPU1_SA_DQ<4>
J 0
(-5890 3985);
DISPLAY 0.659574 (-5890 3985);
PAINT MONO (-5890 3985);
DISPLAY INVISIBLE (-5890 3985);
FORCEPROP 1 LASTPIN (-5900 3975) BN 4
J 0
(-5912 3983);
DISPLAY 0.489362 (-5912 3983);
PAINT GREEN (-5912 3983);
FORCEPROP 2 LAST CDS_LIB mstr_standard
J 0
(-5850 3975);
DISPLAY 0.723404 (-5850 3975);
PAINT MONO (-5850 3975);
DISPLAY INVISIBLE (-5850 3975);
FORCEPROP 1 LAST BODY_TYPE PLUMBING
J 0
(-5850 4025);
DISPLAY 0.872340 (-5850 4025);
PAINT GREEN (-5850 4025);
DISPLAY INVISIBLE (-5850 4025);
FORCEPROP 1 LAST HDL_TAP TRUE
J 0
(-5525 3850);
DISPLAY 0.872340 (-5525 3850);
DISPLAY INVISIBLE (-5525 3850);
FORCEPROP 1 LAST PATH I97
J 0
(-5852 3975);
DISPLAY 0.872340 (-5852 3975);
PAINT GREEN (-5852 3975);
DISPLAY INVISIBLE (-5852 3975);
FORCEADD TAP..1
(-5850 4025);
FORCEPROP 3 LASTPIN (-5900 4025) SIG_NAME M_J_CPU1_SA_DQ<5>
J 0
(-5890 4035);
DISPLAY 0.659574 (-5890 4035);
PAINT MONO (-5890 4035);
DISPLAY INVISIBLE (-5890 4035);
FORCEPROP 1 LASTPIN (-5900 4025) BN 5
J 0
(-5912 4033);
DISPLAY 0.489362 (-5912 4033);
PAINT GREEN (-5912 4033);
FORCEPROP 2 LAST CDS_LIB mstr_standard
J 0
(-5850 4025);
DISPLAY 0.723404 (-5850 4025);
PAINT MONO (-5850 4025);
DISPLAY INVISIBLE (-5850 4025);
FORCEPROP 1 LAST BODY_TYPE PLUMBING
J 0
(-5850 4075);
DISPLAY 0.872340 (-5850 4075);
PAINT GREEN (-5850 4075);
DISPLAY INVISIBLE (-5850 4075);
FORCEPROP 1 LAST HDL_TAP TRUE
J 0
(-5525 3900);
DISPLAY 0.872340 (-5525 3900);
DISPLAY INVISIBLE (-5525 3900);
FORCEPROP 1 LAST PATH I98
J 0
(-5852 4025);
DISPLAY 0.872340 (-5852 4025);
PAINT GREEN (-5852 4025);
DISPLAY INVISIBLE (-5852 4025);
FORCEADD TAP..1
(-5850 4075);
FORCEPROP 3 LASTPIN (-5900 4075) SIG_NAME M_J_CPU1_SA_DQ<6>
J 0
(-5890 4085);
DISPLAY 0.659574 (-5890 4085);
PAINT MONO (-5890 4085);
DISPLAY INVISIBLE (-5890 4085);
FORCEPROP 1 LASTPIN (-5900 4075) BN 6
J 0
(-5912 4083);
DISPLAY 0.489362 (-5912 4083);
PAINT GREEN (-5912 4083);
FORCEPROP 2 LAST CDS_LIB mstr_standard
J 0
(-5850 4075);
DISPLAY 0.723404 (-5850 4075);
PAINT MONO (-5850 4075);
DISPLAY INVISIBLE (-5850 4075);
FORCEPROP 1 LAST BODY_TYPE PLUMBING
J 0
(-5850 4125);
DISPLAY 0.872340 (-5850 4125);
PAINT GREEN (-5850 4125);
DISPLAY INVISIBLE (-5850 4125);
FORCEPROP 1 LAST HDL_TAP TRUE
J 0
(-5525 3950);
DISPLAY 0.872340 (-5525 3950);
DISPLAY INVISIBLE (-5525 3950);
FORCEPROP 1 LAST PATH I99
J 0
(-5852 4075);
DISPLAY 0.872340 (-5852 4075);
PAINT GREEN (-5852 4075);
DISPLAY INVISIBLE (-5852 4075);
FORCEADD QUANTA_TITLE_BLOCK_C..1
(0 0);
FORCEPROP 0 LAST CDS_CON_LAST_MODIFIED Thu Sep 14 16:12:13 2023
J 0
(-1885 15);
DISPLAY INVISIBLE (-1885 15);
FORCEPROP 1 LAST CUSTOM_TXT_CDS <CON_LAST_MODIFIED>
J 0
(-1885 15);
DISPLAY 0.978723 (-1885 15);
FORCEPROP 2 LAST CUSTOM_TXT_CDS <XR_PAGE_TITLE>
J 0
(-7890 5250);
DISPLAY 0.638298 (-7890 5250);
PAINT PINK (-7890 5250);
DISPLAY INVISIBLE (-7890 5250);
FORCEPROP 1 LAST CUSTOM_TXT_CDS <NAME_2>
J 0
(-3175 50);
FORCEPROP 1 LAST CUSTOM_TXT_CDS <NAME_1>
J 0
(-3175 175);
FORCEPROP 1 LAST CUSTOM_TXT_CDS <Q_NUMBER>
J 0
(-1403 103);
DISPLAY 1.212766 (-1403 103);
FORCEPROP 1 LAST CUSTOM_TXT_CDS <Q_PROJ>
J 0
(-2382 102);
DISPLAY 1.212766 (-2382 102);
FORCEPROP 1 LAST CUSTOM_TXT_CDS <Q_REV>
J 0
(-184 103);
DISPLAY 1.212766 (-184 103);
FORCEPROP 1 LAST CUSTOM_TXT_CDS <CON_PAGE_NUM> OF <CON_TOTAL_PAGES>
J 0
(-446 18);
DISPLAY 0.978723 (-446 18);
FORCEPROP 1 LAST Q_TITLE DDR5 - CPU1 CHJ
J 0
(-9366 26);
DISPLAY 2.446809 (-9366 26);
PAINT GREEN (-9366 26);
FORCEPROP 2 LAST CDS_LIB pure_quanta
J 0
(0 0);
DISPLAY INVISIBLE (0 0);
FORCEPROP 1 LAST CDS_LMAN_SYM_OUTLINE -9475,6775,100,-125
J 0
(0 0);
DISPLAY 0.468085 (0 0);
PAINT GREEN (0 0);
DISPLAY INVISIBLE (0 0);
FORCEPROP 2 LAST PAGE_BORDER TRUE
J 0
(-7890 5250);
DISPLAY 0.638298 (-7890 5250);
PAINT PINK (-7890 5250);
DISPLAY INVISIBLE (-7890 5250);
FORCEPROP 2 LAST CDS_XR_PAGE_TITLE CR-107 : @T6G_MB_LIB.T6G(SCH_1):PAGE107
J 0
(-7890 5250);
DISPLAY 0.638298 (-7890 5250);
PAINT PINK (-7890 5250);
DISPLAY INVISIBLE (-7890 5250);
FORCEPROP 1 LAST Q_DEPT BU9
J 1
(-3763 49);
DISPLAY 1.957447 (-3763 49);
PAINT GREEN (-3763 49);
DISPLAY INVISIBLE (-3763 49);
FORCEPROP 1 LAST COMMENT_BODY TRUE
J 0
(12 -13);
DISPLAY 0.978723 (12 -13);
PAINT GREEN (12 -13);
DISPLAY INVISIBLE (12 -13);
FORCEADD DNS..2
(-8225 2225);
PAINT RED (-8225 2225);
FORCEPROP 2 LAST CDS_LIB mstr_misc
J 0
(-8225 2225);
DISPLAY INVISIBLE (-8225 2225);
FORCEPROP 1 LAST COMMENT_BODY TRUE
R 1
J 0
(-8150 2000);
DISPLAY 0.872340 (-8150 2000);
PAINT PEACH (-8150 2000);
DISPLAY INVISIBLE (-8150 2000);
WIRE 17 -1 (-5800 3100)(-5800 3050);
WIRE 17 -1 (-5800 3150)(-5800 3100);
WIRE 17 -1 (-5800 3050)(-5800 3000);
WIRE 17 -1 (-5800 3000)(-5800 2950);
WIRE 17 -1 (-5800 3200)(-5800 3150);
WIRE 17 -1 (-5800 3250)(-5800 3200);
WIRE 17 -1 (-5800 2900)(-5800 2950);
WIRE 17 -1 (-5800 2850)(-5800 2900);
WIRE 17 -1 (-5800 3300)(-5800 3250);
WIRE 17 -1 (-5800 3350)(-5800 3300);
WIRE 17 -1 (-5800 2800)(-5800 2850);
WIRE 17 -1 (-5800 2750)(-5800 2800);
WIRE 17 -1 (-5800 3400)(-5800 3350);
WIRE 17 -1 (-5800 3450)(-5800 3400);
WIRE 17 -1 (-5800 2750)(-5800 2700);
WIRE 17 -1 (-5800 2700)(-5800 2650);
WIRE 17 -1 (-5800 3500)(-5800 3450);
WIRE 17 -1 (-5800 3550)(-5800 3500);
WIRE 17 -1 (-5800 2650)(-5800 2600);
WIRE 17 -1 (-5800 2600)(-5800 2550);
WIRE 17 -1 (-5800 3600)(-5800 3550);
WIRE 17 -1 (-5800 3650)(-5800 3600);
WIRE 17 -1 (-5800 2550)(-5800 2500);
WIRE 17 -1 (-5800 2500)(-5800 2450);
WIRE 17 -1 (-5800 3700)(-5800 3650);
WIRE 17 -1 (-5800 3725)(-5800 3700);
WIRE 17 -1 (-5800 2450)(-5800 2400);
WIRE 17 -1 (-5800 2400)(-5800 2350);
WIRE 17 -1 (-5800 3725)(-5250 3725);
FORCEPROP 2 LAST SIG_NAME M_J_CPU1_SB_DQ<31:0>
J 0
(-5735 3735);
DISPLAY 0.489362 (-5735 3735);
WIRE 17 -1 (-3300 4700)(-3300 4675);
WIRE 17 -1 (-3300 4700)(-2400 4700);
FORCEPROP 2 LAST SIG_NAME M_J_CPU1_SA_DQS_DP<9:0>
J 0
(-3035 4710);
DISPLAY 0.489362 (-3035 4710);
WIRE 17 -1 (-3100 4650)(-3100 4625);
WIRE 17 -1 (-3100 4650)(-2400 4650);
FORCEPROP 2 LAST SIG_NAME M_J_CPU1_SA_DQS_DN<9:0>
J 0
(-3035 4660);
DISPLAY 0.489362 (-3035 4660);
WIRE 17 -1 (-3300 3650)(-3300 3625);
WIRE 17 -1 (-3300 3650)(-2400 3650);
FORCEPROP 2 LAST SIG_NAME M_J_CPU1_SB_DQS_DP<9:0>
J 0
(-3035 3660);
DISPLAY 0.489362 (-3035 3660);
WIRE 17 -1 (-3100 3600)(-3100 3575);
WIRE 17 -1 (-3100 3600)(-2400 3600);
FORCEPROP 2 LAST SIG_NAME M_J_CPU1_SB_DQS_DN<9:0>
J 0
(-3035 3610);
DISPLAY 0.489362 (-3035 3610);
WIRE 17 -1 (-3300 4675)(-3300 4575);
WIRE 17 -1 (-3300 4575)(-3300 4475);
WIRE 17 -1 (-3300 4475)(-3300 4375);
WIRE 17 -1 (-3100 4625)(-3100 4525);
WIRE 17 -1 (-3100 4525)(-3100 4425);
WIRE 17 -1 (-3100 4425)(-3100 4325);
WIRE 17 -1 (-3100 3475)(-3100 3375);
WIRE 17 -1 (-3100 3575)(-3100 3475);
WIRE 17 -1 (-3100 3375)(-3100 3275);
WIRE 17 -1 (-3100 3275)(-3100 3175);
WIRE 17 -1 (-3300 4375)(-3300 4275);
WIRE 17 -1 (-3300 3425)(-3300 3325);
WIRE 17 -1 (-3300 3525)(-3300 3425);
WIRE 17 -1 (-3300 3325)(-3300 3225);
WIRE 17 -1 (-3300 3125)(-3300 3225);
WIRE 17 -1 (-3300 3625)(-3300 3525);
WIRE 17 -1 (-3300 3025)(-3300 3125);
WIRE 17 -1 (-3300 2925)(-3300 3025);
WIRE 17 -1 (-3100 3075)(-3100 3175);
WIRE 17 -1 (-3100 2975)(-3100 3075);
WIRE 17 -1 (-3100 2875)(-3100 2975);
WIRE 17 -1 (-3100 4325)(-3100 4225);
WIRE 17 -1 (-3100 4125)(-3100 4225);
WIRE 17 -1 (-3100 4025)(-3100 4125);
WIRE 17 -1 (-3100 3925)(-3100 4025);
WIRE 17 -1 (-3300 2925)(-3300 2825);
WIRE 17 -1 (-3100 2875)(-3100 2775);
WIRE 17 -1 (-3300 4175)(-3300 4275);
WIRE 17 -1 (-3300 4075)(-3300 4175);
WIRE 17 -1 (-3300 3975)(-3300 4075);
WIRE 17 -1 (-3300 3975)(-3300 3875);
WIRE 17 -1 (-3100 3925)(-3100 3825);
WIRE 17 -1 (-3300 2825)(-3300 2725);
WIRE 17 -1 (-3100 2775)(-3100 2675);
WIRE 17 -1 (-3300 3875)(-3300 3775);
WIRE 17 -1 (-3100 3825)(-3100 3725);
WIRE 17 -1 (-5800 4500)(-5800 4550);
WIRE 17 -1 (-5800 4450)(-5800 4500);
WIRE 17 -1 (-5800 4550)(-5800 4600);
WIRE 17 -1 (-5800 4650)(-5800 4600);
WIRE 17 -1 (-5800 4400)(-5800 4450);
WIRE 17 -1 (-5800 4400)(-5800 4350);
WIRE 17 -1 (-5800 4700)(-5800 4650);
WIRE 17 -1 (-5800 4750)(-5800 4700);
WIRE 17 -1 (-5800 4350)(-5800 4300);
WIRE 17 -1 (-5800 4300)(-5800 4250);
WIRE 17 -1 (-5800 4800)(-5800 4750);
WIRE 17 -1 (-5800 4850)(-5800 4800);
WIRE 17 -1 (-5800 4250)(-5800 4200);
WIRE 17 -1 (-5800 4200)(-5800 4150);
WIRE 17 -1 (-5800 4900)(-5800 4850);
WIRE 17 -1 (-5800 4950)(-5800 4900);
WIRE 17 -1 (-5800 4150)(-5800 4100);
WIRE 17 -1 (-5800 4100)(-5800 4050);
WIRE 17 -1 (-5800 5000)(-5800 4950);
WIRE 17 -1 (-5800 5050)(-5800 5000);
WIRE 17 -1 (-5800 4050)(-5800 4000);
WIRE 17 -1 (-5800 3950)(-5800 4000);
WIRE 17 -1 (-5800 5100)(-5800 5050);
WIRE 17 -1 (-5800 5150)(-5800 5100);
WIRE 17 -1 (-5800 3900)(-5800 3950);
WIRE 17 -1 (-5800 3850)(-5800 3900);
WIRE 17 -1 (-5800 5200)(-5800 5150);
WIRE 17 -1 (-5800 5250)(-5800 5200);
WIRE 17 -1 (-5800 3800)(-5800 3850);
WIRE 17 -1 (-5800 5300)(-5800 5250);
WIRE 17 -1 (-5800 5350)(-5800 5300);
WIRE 17 -1 (-5800 5375)(-5800 5350);
WIRE 17 -1 (-5800 5375)(-5250 5375);
FORCEPROP 2 LAST SIG_NAME M_J_CPU1_SA_DQ<31:0>
J 0
(-5735 5385);
DISPLAY 0.489362 (-5735 5385);
WIRE 17 -1 (-7600 5350)(-7600 5375);
WIRE 17 -1 (-7600 5300)(-7600 5350);
WIRE 17 -1 (-7600 5375)(-8100 5375);
FORCEPROP 2 LAST SIG_NAME M_J_CPU1_SA_CA<6:0>
J 0
(-8085 5385);
DISPLAY 0.489362 (-8085 5385);
WIRE 17 -1 (-7600 5250)(-7600 5300);
WIRE 17 -1 (-7600 5200)(-7600 5250);
WIRE 17 -1 (-7600 5150)(-7600 5200);
WIRE 17 -1 (-7600 5100)(-7600 5150);
WIRE 17 -1 (-7600 5050)(-7600 5100);
WIRE 17 -1 (-5800 2150)(-5800 2200);
WIRE 17 -1 (-5800 2200)(-5800 2250);
WIRE 17 -1 (-5800 2250)(-5800 2300);
WIRE 17 -1 (-5800 2300)(-5800 2350);
WIRE 17 -1 (-7600 3150)(-7600 3200);
WIRE 17 -1 (-7600 3200)(-7600 3250);
WIRE 17 -1 (-7600 3250)(-7600 3300);
WIRE 17 -1 (-7600 3300)(-7600 3350);
WIRE 17 -1 (-7600 3400)(-7600 3350);
WIRE 17 -1 (-7600 3400)(-7600 3450);
WIRE 17 -1 (-7600 3500)(-7600 3450);
WIRE 17 -1 (-7600 3500)(-7600 3525);
WIRE 17 -1 (-7600 3525)(-8100 3525);
FORCEPROP 2 LAST SIG_NAME M_J_CPU1_SB_CB<7:0>
J 0
(-8050 3535);
DISPLAY 0.489362 (-8050 3535);
WIRE 17 -1 (-7600 3600)(-7600 3650);
WIRE 17 -1 (-7600 3650)(-7600 3700);
WIRE 17 -1 (-7600 3700)(-7600 3750);
WIRE 17 -1 (-7600 3750)(-7600 3800);
WIRE 17 -1 (-7600 3850)(-7600 3800);
WIRE 17 -1 (-7600 3850)(-7600 3900);
WIRE 17 -1 (-7600 3950)(-7600 3900);
WIRE 17 -1 (-7600 3950)(-7600 3975);
WIRE 17 -1 (-7600 3975)(-8100 3975);
FORCEPROP 2 LAST SIG_NAME M_J_CPU1_SA_CB<7:0>
J 0
(-8050 3985);
DISPLAY 0.489362 (-8050 3985);
WIRE 17 -1 (-7600 4950)(-7600 4975);
WIRE 17 -1 (-7600 4900)(-7600 4950);
WIRE 17 -1 (-7600 4975)(-8100 4975);
FORCEPROP 2 LAST SIG_NAME M_J_CPU1_SB_CA<6:0>
J 0
(-8085 4985);
DISPLAY 0.489362 (-8085 4985);
WIRE 17 -1 (-7600 4850)(-7600 4900);
WIRE 17 -1 (-7600 4800)(-7600 4850);
WIRE 17 -1 (-7600 4750)(-7600 4800);
WIRE 17 -1 (-7600 4700)(-7600 4750);
WIRE 17 -1 (-7600 4650)(-7600 4700);
WIRE 16 -1 (-6250 1000)(-6250 1075);
WIRE 16 -1 (-8525 2975)(-8525 3050);
WIRE 16 -1 (-8250 2325)(-8250 2350);
WIRE 16 -1 (-7300 2825)(-8350 2825);
FORCEPROP 2 LAST SIG_NAME PD_CHJ_CPU1_DIMM_SAA
J 0
(-8325 2835);
DISPLAY 0.489362 (-8325 2835);
WIRE 16 -1 (-8125 2775)(-8100 2775);
WIRE 16 -1 (-8125 2675)(-8125 2775);
WIRE 16 -1 (-8125 2675)(-8625 2675);
FORCEPROP 2 LAST SIG_NAME I3C_SPD_DDRGL_CPU1_SDA
J 0
(-8635 2685);
DISPLAY 0.489362 (-8635 2685);
WIRE 16 -1 (-7300 2775)(-7900 2775);
FORCEPROP 2 LAST SIG_NAME I3C_SPD_DDRJ_CPU1_SDA
J 0
(-7810 2785);
DISPLAY 0.446809 (-7810 2785);
FORCEPROP 2 LASTPROP $XRERR UNIQUE?
J 0
(-8050 2785);
DISPLAY 0.638298 (-8050 2785);
PAINT MONO (-8050 2785);
DISPLAY INVISIBLE (-8050 2785);
WIRE 16 -1 (-8025 2075)(-8025 2475);
WIRE 16 -1 (-8025 2075)(-8250 2075);
WIRE 16 -1 (-7300 2475)(-8025 2475);
FORCEPROP 2 LAST SIG_NAME PWRGD_CHJ_CPU1_DIMM
J 0
(-7910 2485);
DISPLAY 0.489362 (-7910 2485);
FORCEPROP 2 LASTPROP $XRERR UNIQUE?
J 0
(-8150 2485);
DISPLAY 0.638298 (-8150 2485);
PAINT MONO (-8150 2485);
DISPLAY INVISIBLE (-8150 2485);
WIRE 16 -1 (-8250 2125)(-8250 2075);
WIRE 16 -1 (-8250 2075)(-8275 2075);
WIRE 16 -1 (-7700 2575)(-8125 2575);
FORCEPROP 2 LAST SIG_NAME I3C_SPD_DDRGL_CPU1_SCL
J 0
(-8185 2585);
DISPLAY 0.489362 (-8185 2585);
WIRE 16 -1 (-8525 3250)(-8525 3275);
WIRE 16 -1 (-8525 3275)(-8425 3275);
WIRE 16 -1 (-8425 3300)(-8425 3275);
WIRE 16 -1 (-8425 3275)(-8425 2875);
WIRE 16 -1 (-8425 2875)(-7300 2875);
WIRE 16 -1 (-7400 2725)(-7400 2575);
FORCEPROP 2 LAST SIG_NAME I3C_SPD_DDRJ_CPU1_SCL
J 0
(-7785 2735);
DISPLAY 0.446809 (-7785 2735);
FORCEPROP 2 LASTPROP $XRERR UNIQUE?
J 0
(-8025 2735);
DISPLAY 0.638298 (-8025 2735);
PAINT MONO (-8025 2735);
DISPLAY INVISIBLE (-8025 2735);
WIRE 16 -1 (-7300 2725)(-7400 2725);
WIRE 16 -1 (-7400 2575)(-7500 2575);
WIRE 16 -1 (-7300 4025)(-8100 4025);
FORCEPROP 2 LAST SIG_NAME M_J_CPU1_CLK_DN<0>
J 0
(-8050 4035);
DISPLAY 0.489362 (-8050 4035);
WIRE 16 -1 (-7300 4225)(-8100 4225);
FORCEPROP 2 LAST SIG_NAME M_J_CPU1_SB_CS_N<1>
J 0
(-8050 4235);
DISPLAY 0.489362 (-8050 4235);
WIRE 16 -1 (-7300 2975)(-7900 2975);
FORCEPROP 2 LAST SIG_NAME M_J_CPU1_ALERT_N
J 0
(-7885 2985);
DISPLAY 0.489362 (-7885 2985);
WIRE 16 -1 (-7300 3025)(-7900 3025);
FORCEPROP 2 LAST SIG_NAME M_J_CPU1_RESET_N
J 0
(-7885 3035);
DISPLAY 0.489362 (-7885 3035);
WIRE 16 -1 (-7300 3775)(-7500 3775);
WIRE 16 -1 (-5900 4025)(-6100 4025);
WIRE 16 -1 (-5900 4075)(-6100 4075);
WIRE 16 -1 (-8475 2075)(-8875 2075);
FORCEPROP 2 LAST SIG_NAME PWRGD_CHGL_CPU1
J 0
(-8835 2085);
DISPLAY 0.489362 (-8835 2085);
WIRE 16 -1 (-2150 5975)(-2025 5975);
WIRE 16 -1 (-2150 5975)(-2150 5875);
WIRE 16 -1 (-2150 5975)(-2725 5975);
WIRE 16 -1 (-2025 5225)(-2025 5975);
WIRE 16 -1 (-1725 5225)(-2025 5225);
WIRE 16 -1 (-2025 5175)(-2025 5225);
WIRE 16 -1 (-2725 5875)(-2725 5975);
WIRE 16 -1 (-2725 5975)(-2725 6050);
WIRE 16 -1 (-1725 5175)(-2025 5175);
WIRE 16 -1 (-2025 5175)(-2025 5125);
WIRE 16 -1 (-2025 5125)(-1725 5125);
WIRE 16 -1 (-7300 1925)(-8100 1925);
FORCEPROP 2 LAST SIG_NAME M_J_CPU1_SA_RSP<0>
J 0
(-8050 1935);
DISPLAY 0.489362 (-8050 1935);
WIRE 16 -1 (-6100 2675)(-5900 2675);
WIRE 16 -1 (-2150 5550)(-2150 5675);
WIRE 16 -1 (-2150 5550)(-2725 5550);
WIRE 16 -1 (-2725 5550)(-2725 5675);
WIRE 16 -1 (-2725 5550)(-2725 5475);
WIRE 16 -1 (-6250 1350)(-6250 1275);
WIRE 16 -1 (-6250 1350)(-6975 1350);
FORCEPROP 2 LAST SIG_NAME PD_CHJ_CPU1_DIMM_SAA
J 0
(-6960 1360);
DISPLAY 0.489362 (-6960 1360);
WIRE 16 -1 (-6100 5325)(-5900 5325);
WIRE 16 -1 (-7300 3925)(-7500 3925);
WIRE 16 -1 (-7300 3625)(-7500 3625);
WIRE 16 -1 (-7300 3475)(-7500 3475);
WIRE 16 -1 (-7300 5025)(-7500 5025);
WIRE 16 -1 (-7300 4625)(-7500 4625);
WIRE 16 -1 (-7300 5075)(-7500 5075);
WIRE 16 -1 (-7300 4675)(-7500 4675);
WIRE 16 -1 (-7300 5125)(-7500 5125);
WIRE 16 -1 (-7300 4725)(-7500 4725);
WIRE 16 -1 (-7300 4775)(-7500 4775);
WIRE 16 -1 (-7300 5225)(-7500 5225);
WIRE 16 -1 (-7300 4825)(-7500 4825);
WIRE 16 -1 (-7300 4875)(-7500 4875);
WIRE 16 -1 (-7300 4925)(-7500 4925);
WIRE 16 -1 (-7300 3875)(-7500 3875);
WIRE 16 -1 (-7300 3825)(-7500 3825);
WIRE 16 -1 (-7300 3725)(-7500 3725);
WIRE 16 -1 (-7300 3675)(-7500 3675);
WIRE 16 -1 (-7300 3575)(-7500 3575);
WIRE 16 -1 (-7300 3425)(-7500 3425);
WIRE 16 -1 (-7300 3375)(-7500 3375);
WIRE 16 -1 (-7300 3325)(-7500 3325);
WIRE 16 -1 (-7300 3275)(-7500 3275);
WIRE 16 -1 (-7300 3225)(-7500 3225);
WIRE 16 -1 (-7300 3175)(-7500 3175);
WIRE 16 -1 (-7300 3125)(-7500 3125);
WIRE 16 -1 (-7300 4075)(-8100 4075);
FORCEPROP 2 LAST SIG_NAME M_J_CPU1_CLK_DP<0>
J 0
(-8050 4085);
DISPLAY 0.489362 (-8050 4085);
WIRE 16 -1 (-7300 4175)(-8100 4175);
FORCEPROP 2 LAST SIG_NAME M_J_CPU1_SB_CS_N<0>
J 0
(-8050 4185);
DISPLAY 0.489362 (-8050 4185);
WIRE 16 -1 (-7300 4375)(-8100 4375);
FORCEPROP 2 LAST SIG_NAME M_J_CPU1_SA_CS_N<1>
J 0
(-8050 4385);
DISPLAY 0.489362 (-8050 4385);
WIRE 16 -1 (-5900 5275)(-6100 5275);
WIRE 16 -1 (-5900 5175)(-6100 5175);
WIRE 16 -1 (-6100 5125)(-5900 5125);
WIRE 16 -1 (-5900 5075)(-6100 5075);
WIRE 16 -1 (-5900 5025)(-6100 5025);
WIRE 16 -1 (-5900 4775)(-6100 4775);
WIRE 16 -1 (-6100 4725)(-5900 4725);
WIRE 16 -1 (-5900 4675)(-6100 4675);
WIRE 16 -1 (-5900 4625)(-6100 4625);
WIRE 16 -1 (-5900 4575)(-6100 4575);
WIRE 16 -1 (-5900 4475)(-6100 4475);
WIRE 16 -1 (-5900 4425)(-6100 4425);
WIRE 16 -1 (-5900 4375)(-6100 4375);
WIRE 16 -1 (-6100 4325)(-5900 4325);
WIRE 16 -1 (-5900 4275)(-6100 4275);
WIRE 16 -1 (-5900 4225)(-6100 4225);
WIRE 16 -1 (-5900 4175)(-6100 4175);
WIRE 16 -1 (-6100 4125)(-5900 4125);
WIRE 16 -1 (-5900 3975)(-6100 3975);
WIRE 16 -1 (-6100 3925)(-5900 3925);
WIRE 16 -1 (-5900 3875)(-6100 3875);
WIRE 16 -1 (-5900 3825)(-6100 3825);
WIRE 16 -1 (-5900 3775)(-6100 3775);
WIRE 16 -1 (-6100 3675)(-5900 3675);
WIRE 16 -1 (-5900 3625)(-6100 3625);
WIRE 16 -1 (-5900 3575)(-6100 3575);
WIRE 16 -1 (-5900 3525)(-6100 3525);
WIRE 16 -1 (-6100 3475)(-5900 3475);
WIRE 16 -1 (-5900 3425)(-6100 3425);
WIRE 16 -1 (-5900 3375)(-6100 3375);
WIRE 16 -1 (-5900 3325)(-6100 3325);
WIRE 16 -1 (-6100 3275)(-5900 3275);
WIRE 16 -1 (-5900 3225)(-6100 3225);
WIRE 16 -1 (-5900 3175)(-6100 3175);
WIRE 16 -1 (-6100 3075)(-5900 3075);
WIRE 16 -1 (-5900 2975)(-6100 2975);
WIRE 16 -1 (-5900 2925)(-6100 2925);
WIRE 16 -1 (-6100 2875)(-5900 2875);
WIRE 16 -1 (-5900 2825)(-6100 2825);
WIRE 16 -1 (-5900 2775)(-6100 2775);
WIRE 16 -1 (-5900 2725)(-6100 2725);
WIRE 16 -1 (-5900 2625)(-6100 2625);
WIRE 16 -1 (-5900 2575)(-6100 2575);
WIRE 16 -1 (-5900 2525)(-6100 2525);
WIRE 16 -1 (-6100 2475)(-5900 2475);
WIRE 16 -1 (-5900 2425)(-6100 2425);
WIRE 16 -1 (-5900 2375)(-6100 2375);
WIRE 16 -1 (-5900 2325)(-6100 2325);
WIRE 16 -1 (-6100 2275)(-5900 2275);
WIRE 16 -1 (-5900 2225)(-6100 2225);
WIRE 16 -1 (-5900 2175)(-6100 2175);
WIRE 16 -1 (-5900 2125)(-6100 2125);
WIRE 16 -1 (-7300 1875)(-8100 1875);
FORCEPROP 2 LAST SIG_NAME M_J_CPU1_SB_RSP<0>
J 0
(-8050 1885);
DISPLAY 0.489362 (-8050 1885);
WIRE 16 -1 (-7300 4525)(-8100 4525);
FORCEPROP 2 LAST SIG_NAME M_J_CPU1_SA_PAR
J 0
(-8050 4535);
DISPLAY 0.489362 (-8050 4535);
WIRE 16 -1 (-7300 4475)(-8100 4475);
FORCEPROP 2 LAST SIG_NAME M_J_CPU1_SB_PAR
J 0
(-8050 4485);
DISPLAY 0.489362 (-8050 4485);
WIRE 16 -1 (-5900 5225)(-6100 5225);
WIRE 16 -1 (-5900 4825)(-6100 4825);
WIRE 16 -1 (-5900 4875)(-6100 4875);
WIRE 16 -1 (-7300 5175)(-7500 5175);
WIRE 16 -1 (-7300 5275)(-7500 5275);
WIRE 16 -1 (-7300 5325)(-7500 5325);
WIRE 16 -1 (-5900 4975)(-6100 4975);
WIRE 16 -1 (-6100 4925)(-5900 4925);
WIRE 16 -1 (-6100 4525)(-5900 4525);
WIRE 16 -1 (-3550 4400)(-3200 4400);
WIRE 16 -1 (-3400 4350)(-3550 4350);
WIRE 16 -1 (-3400 3500)(-3550 3500);
WIRE 16 -1 (-3550 3450)(-3200 3450);
WIRE 16 -1 (-3400 3400)(-3550 3400);
WIRE 16 -1 (-3550 3700)(-3200 3700);
WIRE 16 -1 (-3400 3750)(-3550 3750);
WIRE 16 -1 (-3550 2650)(-3200 2650);
WIRE 16 -1 (-3400 2700)(-3550 2700);
WIRE 16 -1 (-3550 3800)(-3200 3800);
WIRE 16 -1 (-3550 3850)(-3400 3850);
WIRE 16 -1 (-3550 2750)(-3200 2750);
WIRE 16 -1 (-3550 2800)(-3400 2800);
WIRE 16 -1 (-3550 3900)(-3200 3900);
WIRE 16 -1 (-3400 3950)(-3550 3950);
WIRE 16 -1 (-3550 2850)(-3200 2850);
WIRE 16 -1 (-3400 2900)(-3550 2900);
WIRE 16 -1 (-3550 4000)(-3200 4000);
WIRE 16 -1 (-3400 4050)(-3550 4050);
WIRE 16 -1 (-3550 2950)(-3200 2950);
WIRE 16 -1 (-3400 3000)(-3550 3000);
WIRE 16 -1 (-3550 4100)(-3200 4100);
WIRE 16 -1 (-3400 4150)(-3550 4150);
WIRE 16 -1 (-3550 3050)(-3200 3050);
WIRE 16 -1 (-3400 3100)(-3550 3100);
WIRE 16 -1 (-3550 4200)(-3200 4200);
WIRE 16 -1 (-3550 4250)(-3400 4250);
WIRE 16 -1 (-3550 3150)(-3200 3150);
WIRE 16 -1 (-3550 3200)(-3400 3200);
WIRE 16 -1 (-3550 4300)(-3200 4300);
WIRE 16 -1 (-3550 3250)(-3200 3250);
WIRE 16 -1 (-3400 3300)(-3550 3300);
WIRE 16 -1 (-3400 4450)(-3550 4450);
WIRE 16 -1 (-3550 3350)(-3200 3350);
WIRE 16 -1 (-3550 4500)(-3200 4500);
WIRE 16 -1 (-3400 4550)(-3550 4550);
WIRE 16 -1 (-3550 3550)(-3200 3550);
WIRE 16 -1 (-3550 3600)(-3400 3600);
WIRE 16 -1 (-3550 4600)(-3200 4600);
WIRE 16 -1 (-3550 4650)(-3400 4650);
WIRE 16 -1 (-225 5225)(-225 5175);
WIRE 16 -1 (-225 5225)(-525 5225);
WIRE 16 -1 (-225 5175)(-225 5125);
WIRE 16 -1 (-225 5175)(-525 5175);
WIRE 16 -1 (-225 5125)(-525 5125);
WIRE 16 -1 (-225 5125)(-225 5075);
WIRE 16 -1 (-225 5075)(-225 5025);
WIRE 16 -1 (-225 5075)(-525 5075);
WIRE 16 -1 (-225 5025)(-225 4975);
WIRE 16 -1 (-225 5025)(-525 5025);
WIRE 16 -1 (-225 4975)(-225 4925);
WIRE 16 -1 (-225 4975)(-525 4975);
WIRE 16 -1 (-225 4925)(-225 4875);
WIRE 16 -1 (-225 4925)(-525 4925);
WIRE 16 -1 (-225 4875)(-225 4825);
WIRE 16 -1 (-225 4875)(-525 4875);
WIRE 16 -1 (-225 4825)(-225 4775);
WIRE 16 -1 (-225 4825)(-525 4825);
WIRE 16 -1 (-225 4775)(-225 4725);
WIRE 16 -1 (-225 4775)(-525 4775);
WIRE 16 -1 (-225 4725)(-225 4675);
WIRE 16 -1 (-225 4725)(-525 4725);
WIRE 16 -1 (-225 4675)(-225 4625);
WIRE 16 -1 (-225 4675)(-525 4675);
WIRE 16 -1 (-225 4625)(-225 4575);
WIRE 16 -1 (-225 4625)(-525 4625);
WIRE 16 -1 (-225 4575)(-225 4525);
WIRE 16 -1 (-225 4575)(-525 4575);
WIRE 16 -1 (-225 4525)(-225 4475);
WIRE 16 -1 (-225 4525)(-525 4525);
WIRE 16 -1 (-225 4475)(-225 4425);
WIRE 16 -1 (-225 4475)(-525 4475);
WIRE 16 -1 (-225 4425)(-225 4375);
WIRE 16 -1 (-225 4425)(-525 4425);
WIRE 16 -1 (-225 4375)(-225 4325);
WIRE 16 -1 (-225 4375)(-525 4375);
WIRE 16 -1 (-225 4325)(-225 4275);
WIRE 16 -1 (-225 4325)(-525 4325);
WIRE 16 -1 (-225 4275)(-225 4225);
WIRE 16 -1 (-225 4275)(-525 4275);
WIRE 16 -1 (-225 4225)(-225 4175);
WIRE 16 -1 (-225 4225)(-525 4225);
WIRE 16 -1 (-225 4175)(-225 4125);
WIRE 16 -1 (-225 4175)(-525 4175);
WIRE 16 -1 (-225 4125)(-525 4125);
WIRE 16 -1 (-225 4125)(-225 4075);
WIRE 16 -1 (-225 4075)(-225 4025);
WIRE 16 -1 (-225 4075)(-525 4075);
WIRE 16 -1 (-225 4025)(-225 3975);
WIRE 16 -1 (-225 4025)(-525 4025);
WIRE 16 -1 (-225 3975)(-225 3925);
WIRE 16 -1 (-225 3975)(-525 3975);
WIRE 16 -1 (-225 3925)(-225 3875);
WIRE 16 -1 (-225 3925)(-525 3925);
WIRE 16 -1 (-225 3875)(-225 3825);
WIRE 16 -1 (-225 3875)(-525 3875);
WIRE 16 -1 (-225 3825)(-225 3775);
WIRE 16 -1 (-225 3825)(-525 3825);
WIRE 16 -1 (-225 3775)(-225 3725);
WIRE 16 -1 (-225 3775)(-525 3775);
WIRE 16 -1 (-225 3725)(-225 3675);
WIRE 16 -1 (-225 3725)(-525 3725);
WIRE 16 -1 (-225 3675)(-225 3625);
WIRE 16 -1 (-225 3675)(-525 3675);
WIRE 16 -1 (-225 3625)(-225 3575);
WIRE 16 -1 (-225 3625)(-525 3625);
WIRE 16 -1 (-225 3575)(-225 3525);
WIRE 16 -1 (-225 3575)(-525 3575);
WIRE 16 -1 (-225 3525)(-225 3475);
WIRE 16 -1 (-225 3525)(-525 3525);
WIRE 16 -1 (-225 3475)(-225 3425);
WIRE 16 -1 (-225 3475)(-525 3475);
WIRE 16 -1 (-225 3425)(-225 3375);
WIRE 16 -1 (-225 3425)(-525 3425);
WIRE 16 -1 (-225 3375)(-225 3325);
WIRE 16 -1 (-225 3375)(-525 3375);
WIRE 16 -1 (-225 3325)(-225 3275);
WIRE 16 -1 (-225 3325)(-525 3325);
WIRE 16 -1 (-225 3275)(-225 3225);
WIRE 16 -1 (-225 3275)(-525 3275);
WIRE 16 -1 (-225 3225)(-225 3175);
WIRE 16 -1 (-225 3225)(-525 3225);
WIRE 16 -1 (-225 3175)(-225 3125);
WIRE 16 -1 (-225 3175)(-525 3175);
WIRE 16 -1 (-225 3125)(-225 3075);
WIRE 16 -1 (-225 3125)(-525 3125);
WIRE 16 -1 (-225 3075)(-525 3075);
WIRE 16 -1 (-225 3075)(-225 3025);
WIRE 16 -1 (-225 3025)(-225 2975);
WIRE 16 -1 (-225 3025)(-525 3025);
WIRE 16 -1 (-225 2975)(-225 2925);
WIRE 16 -1 (-225 2975)(-525 2975);
WIRE 16 -1 (-225 2925)(-225 2875);
WIRE 16 -1 (-225 2925)(-525 2925);
WIRE 16 -1 (-225 2875)(-225 2825);
WIRE 16 -1 (-225 2875)(-525 2875);
WIRE 16 -1 (-225 2825)(-225 2775);
WIRE 16 -1 (-225 2825)(-525 2825);
WIRE 16 -1 (-225 2775)(-225 2725);
WIRE 16 -1 (-225 2775)(-525 2775);
WIRE 16 -1 (-225 2725)(-225 2675);
WIRE 16 -1 (-225 2725)(-525 2725);
WIRE 16 -1 (-225 2675)(-225 2625);
WIRE 16 -1 (-225 2675)(-525 2675);
WIRE 16 -1 (-225 2625)(-225 2575);
WIRE 16 -1 (-225 2625)(-525 2625);
WIRE 16 -1 (-225 2575)(-225 2525);
WIRE 16 -1 (-225 2575)(-525 2575);
WIRE 16 -1 (-225 2525)(-225 2475);
WIRE 16 -1 (-225 2525)(-525 2525);
WIRE 16 -1 (-225 2475)(-225 2425);
WIRE 16 -1 (-225 2475)(-525 2475);
WIRE 16 -1 (-225 2425)(-225 2375);
WIRE 16 -1 (-225 2425)(-525 2425);
WIRE 16 -1 (-225 2375)(-225 2325);
WIRE 16 -1 (-225 2375)(-525 2375);
WIRE 16 -1 (-225 2325)(-225 2275);
WIRE 16 -1 (-225 2325)(-525 2325);
WIRE 16 -1 (-225 2275)(-225 2225);
WIRE 16 -1 (-225 2275)(-525 2275);
WIRE 16 -1 (-225 2225)(-225 2175);
WIRE 16 -1 (-225 2225)(-525 2225);
WIRE 16 -1 (-225 2175)(-225 2125);
WIRE 16 -1 (-225 2175)(-525 2175);
WIRE 16 -1 (-225 2125)(-225 2075);
WIRE 16 -1 (-225 2125)(-525 2125);
WIRE 16 -1 (-225 2075)(-525 2075);
WIRE 16 -1 (-225 2075)(-225 1975);
WIRE 16 -1 (-225 1975)(-225 1925);
WIRE 16 -1 (-225 1975)(-525 1975);
WIRE 16 -1 (-225 1925)(-225 1875);
WIRE 16 -1 (-225 1925)(-525 1925);
WIRE 16 -1 (-225 1875)(-225 1625);
WIRE 16 -1 (-225 1875)(-525 1875);
WIRE 16 -1 (-1725 2075)(-2025 2075);
WIRE 16 -1 (-2025 2125)(-2025 2075);
WIRE 16 -1 (-2025 2075)(-2025 2025);
WIRE 16 -1 (-1725 2025)(-2025 2025);
WIRE 16 -1 (-2025 2025)(-2025 1975);
WIRE 16 -1 (-1725 2125)(-2025 2125);
WIRE 16 -1 (-2025 2175)(-2025 2125);
WIRE 16 -1 (-1725 2175)(-2025 2175);
WIRE 16 -1 (-2025 2225)(-2025 2175);
WIRE 16 -1 (-1725 1975)(-2025 1975);
WIRE 16 -1 (-2025 1975)(-2025 1850);
WIRE 16 -1 (-1725 2225)(-2025 2225);
WIRE 16 -1 (-2025 2275)(-2025 2225);
WIRE 16 -1 (-1725 2275)(-2025 2275);
WIRE 16 -1 (-2025 2325)(-2025 2275);
WIRE 16 -1 (-1725 2325)(-2025 2325);
WIRE 16 -1 (-2025 2375)(-2025 2325);
WIRE 16 -1 (-1725 2375)(-2025 2375);
WIRE 16 -1 (-2025 2425)(-2025 2375);
WIRE 16 -1 (-1725 2425)(-2025 2425);
WIRE 16 -1 (-2025 2475)(-2025 2425);
WIRE 16 -1 (-1725 2475)(-2025 2475);
WIRE 16 -1 (-2025 2525)(-2025 2475);
WIRE 16 -1 (-2025 2575)(-2025 2525);
WIRE 16 -1 (-1725 2525)(-2025 2525);
WIRE 16 -1 (-1725 2575)(-2025 2575);
WIRE 16 -1 (-2025 2625)(-2025 2575);
WIRE 16 -1 (-1725 2625)(-2025 2625);
WIRE 16 -1 (-2025 2675)(-2025 2625);
WIRE 16 -1 (-1725 2675)(-2025 2675);
WIRE 16 -1 (-2025 2725)(-2025 2675);
WIRE 16 -1 (-1725 2725)(-2025 2725);
WIRE 16 -1 (-2025 2775)(-2025 2725);
WIRE 16 -1 (-1725 2775)(-2025 2775);
WIRE 16 -1 (-2025 2825)(-2025 2775);
WIRE 16 -1 (-1725 2825)(-2025 2825);
WIRE 16 -1 (-2025 2875)(-2025 2825);
WIRE 16 -1 (-1725 2875)(-2025 2875);
WIRE 16 -1 (-2025 2925)(-2025 2875);
WIRE 16 -1 (-1725 2925)(-2025 2925);
WIRE 16 -1 (-2025 2975)(-2025 2925);
WIRE 16 -1 (-1725 2975)(-2025 2975);
WIRE 16 -1 (-2025 3025)(-2025 2975);
WIRE 16 -1 (-2025 3075)(-2025 3025);
WIRE 16 -1 (-1725 3025)(-2025 3025);
WIRE 16 -1 (-1725 3075)(-2025 3075);
WIRE 16 -1 (-2025 3125)(-2025 3075);
WIRE 16 -1 (-1725 3125)(-2025 3125);
WIRE 16 -1 (-2025 3175)(-2025 3125);
WIRE 16 -1 (-1725 3175)(-2025 3175);
WIRE 16 -1 (-2025 3225)(-2025 3175);
WIRE 16 -1 (-1725 3225)(-2025 3225);
WIRE 16 -1 (-2025 3275)(-2025 3225);
WIRE 16 -1 (-1725 3275)(-2025 3275);
WIRE 16 -1 (-2025 3325)(-2025 3275);
WIRE 16 -1 (-1725 3325)(-2025 3325);
WIRE 16 -1 (-2025 3375)(-2025 3325);
WIRE 16 -1 (-1725 3375)(-2025 3375);
WIRE 16 -1 (-2025 3425)(-2025 3375);
WIRE 16 -1 (-1725 3425)(-2025 3425);
WIRE 16 -1 (-2025 3475)(-2025 3425);
WIRE 16 -1 (-1725 3475)(-2025 3475);
WIRE 16 -1 (-2025 3525)(-2025 3475);
WIRE 16 -1 (-1725 3525)(-2025 3525);
WIRE 16 -1 (-2025 3575)(-2025 3525);
WIRE 16 -1 (-2025 3625)(-2025 3575);
WIRE 16 -1 (-1725 3575)(-2025 3575);
WIRE 16 -1 (-1725 3625)(-2025 3625);
WIRE 16 -1 (-2025 3675)(-2025 3625);
WIRE 16 -1 (-1725 3675)(-2025 3675);
WIRE 16 -1 (-2025 3725)(-2025 3675);
WIRE 16 -1 (-1725 3725)(-2025 3725);
WIRE 16 -1 (-2025 3775)(-2025 3725);
WIRE 16 -1 (-1725 3775)(-2025 3775);
WIRE 16 -1 (-2025 3825)(-2025 3775);
WIRE 16 -1 (-1725 3825)(-2025 3825);
WIRE 16 -1 (-2025 3875)(-2025 3825);
WIRE 16 -1 (-1725 3875)(-2025 3875);
WIRE 16 -1 (-2025 3925)(-2025 3875);
WIRE 16 -1 (-1725 3925)(-2025 3925);
WIRE 16 -1 (-2025 3975)(-2025 3925);
WIRE 16 -1 (-1725 3975)(-2025 3975);
WIRE 16 -1 (-2025 4025)(-2025 3975);
WIRE 16 -1 (-1725 4025)(-2025 4025);
WIRE 16 -1 (-2025 4075)(-2025 4025);
WIRE 16 -1 (-2025 4125)(-2025 4075);
WIRE 16 -1 (-1725 4075)(-2025 4075);
WIRE 16 -1 (-1725 4125)(-2025 4125);
WIRE 16 -1 (-2025 4175)(-2025 4125);
WIRE 16 -1 (-1725 4175)(-2025 4175);
WIRE 16 -1 (-2025 4225)(-2025 4175);
WIRE 16 -1 (-1725 4225)(-2025 4225);
WIRE 16 -1 (-2025 4275)(-2025 4225);
WIRE 16 -1 (-1725 4275)(-2025 4275);
WIRE 16 -1 (-2025 4325)(-2025 4275);
WIRE 16 -1 (-1725 4325)(-2025 4325);
WIRE 16 -1 (-2025 4375)(-2025 4325);
WIRE 16 -1 (-1725 4375)(-2025 4375);
WIRE 16 -1 (-2025 4425)(-2025 4375);
WIRE 16 -1 (-1725 4425)(-2025 4425);
WIRE 16 -1 (-2025 4475)(-2025 4425);
WIRE 16 -1 (-1725 4475)(-2025 4475);
WIRE 16 -1 (-2025 4525)(-2025 4475);
WIRE 16 -1 (-1725 4525)(-2025 4525);
WIRE 16 -1 (-2025 4575)(-2025 4525);
WIRE 16 -1 (-2025 4625)(-2025 4575);
WIRE 16 -1 (-1725 4575)(-2025 4575);
WIRE 16 -1 (-1725 4625)(-2025 4625);
WIRE 16 -1 (-2025 4675)(-2025 4625);
WIRE 16 -1 (-1725 4675)(-2025 4675);
WIRE 16 -1 (-2025 4725)(-2025 4675);
WIRE 16 -1 (-1725 4725)(-2025 4725);
WIRE 16 -1 (-2025 4775)(-2025 4725);
WIRE 16 -1 (-1725 4775)(-2025 4775);
WIRE 16 -1 (-2025 4825)(-2025 4775);
WIRE 16 -1 (-1725 4825)(-2025 4825);
WIRE 16 -1 (-2025 4875)(-2025 4825);
WIRE 16 -1 (-1725 4875)(-2025 4875);
WIRE 16 -1 (-2025 4925)(-2025 4875);
WIRE 16 -1 (-1725 4925)(-2025 4925);
WIRE 16 -1 (-2025 4975)(-2025 4925);
WIRE 16 -1 (-1725 4975)(-2025 4975);
WIRE 16 -1 (-2025 5025)(-2025 4975);
WIRE 16 -1 (-1725 5025)(-2025 5025);
WIRE 16 -1 (-2025 5075)(-2025 5025);
WIRE 16 -1 (-1725 5075)(-2025 5075);
WIRE 16 -1 (-7300 4325)(-8100 4325);
FORCEPROP 2 LAST SIG_NAME M_J_CPU1_SA_CS_N<0>
J 0
(-8050 4335);
DISPLAY 0.489362 (-8050 4335);
WIRE 16 -1 (-5900 3125)(-6100 3125);
WIRE 16 -1 (-5900 3025)(-6100 3025);
DOT 1 (-8425 3275);
DOT 1 (-2025 4925);
DOT 1 (-2025 4975);
DOT 1 (-225 5175);
DOT 1 (-225 5125);
DOT 1 (-225 5025);
DOT 1 (-225 5075);
DOT 1 (-225 4925);
DOT 1 (-225 4975);
DOT 1 (-225 4875);
DOT 1 (-225 4775);
DOT 1 (-225 4825);
DOT 1 (-225 4725);
DOT 1 (-225 4675);
DOT 1 (-225 4625);
DOT 1 (-225 4525);
DOT 1 (-225 4575);
DOT 1 (-225 4375);
DOT 1 (-225 4475);
DOT 1 (-225 4425);
DOT 1 (-225 4275);
DOT 1 (-225 4325);
DOT 1 (-225 4225);
DOT 1 (-225 4125);
DOT 1 (-225 4175);
DOT 1 (-225 4025);
DOT 1 (-225 4075);
DOT 1 (-225 3975);
DOT 1 (-225 3875);
DOT 1 (-225 3925);
DOT 1 (-225 3775);
DOT 1 (-225 3825);
DOT 1 (-225 3725);
DOT 1 (-2025 5175);
DOT 1 (-2025 5225);
DOT 1 (-2025 5025);
DOT 1 (-2025 4875);
DOT 1 (-2025 4775);
DOT 1 (-2025 4825);
DOT 1 (-2025 4725);
DOT 1 (-2025 4675);
DOT 1 (-2025 4625);
DOT 1 (-2025 4525);
DOT 1 (-2025 4575);
DOT 1 (-2025 4475);
DOT 1 (-2025 4375);
DOT 1 (-2025 4425);
DOT 1 (-2025 4325);
DOT 1 (-2025 4275);
DOT 1 (-2025 4225);
DOT 1 (-2025 4125);
DOT 1 (-2025 4175);
DOT 1 (-2025 4025);
DOT 1 (-2025 4075);
DOT 1 (-2025 3975);
DOT 1 (-2025 3925);
DOT 1 (-2025 3875);
DOT 1 (-2025 3825);
DOT 1 (-2025 3775);
DOT 1 (-2025 3725);
DOT 1 (-225 3625);
DOT 1 (-225 3675);
DOT 1 (-225 3525);
DOT 1 (-225 3575);
DOT 1 (-225 3475);
DOT 1 (-225 3375);
DOT 1 (-225 3425);
DOT 1 (-225 3225);
DOT 1 (-225 3325);
DOT 1 (-225 3275);
DOT 1 (-225 3125);
DOT 1 (-225 3175);
DOT 1 (-225 2975);
DOT 1 (-225 3075);
DOT 1 (-225 3025);
DOT 1 (-225 2875);
DOT 1 (-225 2925);
DOT 1 (-225 2825);
DOT 1 (-225 2725);
DOT 1 (-225 2775);
DOT 1 (-225 2675);
DOT 1 (-225 2625);
DOT 1 (-225 2575);
DOT 1 (-225 2475);
DOT 1 (-225 2525);
DOT 1 (-225 2325);
DOT 1 (-225 2425);
DOT 1 (-225 2375);
DOT 1 (-225 2225);
DOT 1 (-225 2275);
DOT 1 (-225 2175);
DOT 1 (-225 2075);
DOT 1 (-225 2125);
DOT 1 (-225 1975);
DOT 1 (-225 1875);
DOT 1 (-225 1925);
DOT 1 (-2025 3625);
DOT 1 (-2025 3675);
DOT 1 (-2025 3575);
DOT 1 (-2025 3525);
DOT 1 (-2025 3475);
DOT 1 (-2025 3375);
DOT 1 (-2025 3425);
DOT 1 (-2025 3325);
DOT 1 (-2025 3225);
DOT 1 (-2025 3275);
DOT 1 (-2025 3125);
DOT 1 (-2025 3175);
DOT 1 (-2025 3075);
DOT 1 (-2025 2975);
DOT 1 (-2025 3025);
DOT 1 (-2025 2875);
DOT 1 (-2025 2925);
DOT 1 (-2025 2825);
DOT 1 (-2025 2725);
DOT 1 (-2025 2775);
DOT 1 (-2025 2675);
DOT 1 (-2025 2625);
DOT 1 (-2025 2575);
DOT 1 (-2025 2475);
DOT 1 (-2025 2525);
DOT 1 (-2025 2425);
DOT 1 (-2025 2325);
DOT 1 (-2025 2375);
DOT 1 (-2025 2225);
DOT 1 (-2025 2275);
DOT 1 (-2025 2175);
DOT 1 (-2025 2075);
DOT 1 (-2025 2125);
DOT 1 (-2025 1975);
DOT 1 (-2025 2025);
DOT 1 (-2725 5550);
DOT 1 (-2725 5975);
DOT 1 (-2150 5975);
DOT 1 (-8250 2075);
QUIT
